(kicad_sch
	(version 20250114)
	(generator "eeschema")
	(generator_version "9.0")
	(paper "A3")
	(title_block
		(title "Artix - Datacenter Secure Control Module (DC-SCM)")
		(date "2024-11-06")
		(rev "1.1.3")
	)
	(text "Edge connector"
		(exclude_from_sim no)
		(at 203.2 31.75 0)
		(effects
			(font
				(size 2 2)
				(thickness 0.5994)
				(bold yes)
			)
			(justify left bottom)
		)
	)
	(text "Connection according to rev 1.0 draft"
		(exclude_from_sim no)
		(at 259.08 226.06 0)
		(effects
			(font
				(size 1.27 1.27)
			)
			(justify left bottom)
		)
	)
	(text "Connection according to rev 1.0 draft"
		(exclude_from_sim no)
		(at 255.27 96.52 0)
		(effects
			(font
				(size 1.27 1.27)
			)
			(justify left bottom)
		)
	)
	(text "Connection according to rev 1.0 draft"
		(exclude_from_sim no)
		(at 255.27 167.64 0)
		(effects
			(font
				(size 1.27 1.27)
			)
			(justify left bottom)
		)
	)
	(junction
		(at 269.24 67.31)
		(diameter 0)
		(color 0 0 0 0)
	)
	(junction
		(at 171.45 133.35)
		(diameter 0)
		(color 0 0 0 0)
	)
	(junction
		(at 171.45 250.19)
		(diameter 0)
		(color 0 0 0 0)
	)
	(junction
		(at 257.81 265.43)
		(diameter 0)
		(color 0 0 0 0)
	)
	(junction
		(at 257.81 242.57)
		(diameter 0)
		(color 0 0 0 0)
	)
	(junction
		(at 274.32 72.39)
		(diameter 0)
		(color 0 0 0 0)
	)
	(junction
		(at 257.81 250.19)
		(diameter 0)
		(color 0 0 0 0)
	)
	(junction
		(at 248.92 212.09)
		(diameter 0)
		(color 0 0 0 0)
	)
	(junction
		(at 260.35 46.99)
		(diameter 0)
		(color 0 0 0 0)
	)
	(junction
		(at 171.45 265.43)
		(diameter 0)
		(color 0 0 0 0)
	)
	(junction
		(at 229.87 39.37)
		(diameter 0)
		(color 0 0 0 0)
	)
	(junction
		(at 266.7 64.77)
		(diameter 0)
		(color 0 0 0 0)
	)
	(junction
		(at 171.45 118.11)
		(diameter 0)
		(color 0 0 0 0)
	)
	(junction
		(at 199.39 44.45)
		(diameter 0)
		(color 0 0 0 0)
	)
	(junction
		(at 267.97 171.45)
		(diameter 0)
		(color 0 0 0 0)
	)
	(junction
		(at 271.78 69.85)
		(diameter 0)
		(color 0 0 0 0)
	)
	(junction
		(at 260.35 54.61)
		(diameter 0)
		(color 0 0 0 0)
	)
	(junction
		(at 171.45 125.73)
		(diameter 0)
		(color 0 0 0 0)
	)
	(junction
		(at 248.92 219.71)
		(diameter 0)
		(color 0 0 0 0)
	)
	(junction
		(at 171.45 242.57)
		(diameter 0)
		(color 0 0 0 0)
	)
	(junction
		(at 257.81 257.81)
		(diameter 0)
		(color 0 0 0 0)
	)
	(junction
		(at 199.39 39.37)
		(diameter 0)
		(color 0 0 0 0)
	)
	(junction
		(at 171.45 257.81)
		(diameter 0)
		(color 0 0 0 0)
	)
	(wire
		(pts
			(xy 179.07 209.55) (xy 201.93 209.55)
		)
		(stroke
			(width 0)
			(type default)
		)
	)
	(wire
		(pts
			(xy 201.93 130.81) (xy 198.12 130.81)
		)
		(stroke
			(width 0)
			(type default)
		)
	)
	(wire
		(pts
			(xy 201.93 95.25) (xy 198.12 95.25)
		)
		(stroke
			(width 0)
			(type default)
		)
	)
	(wire
		(pts
			(xy 201.93 232.41) (xy 196.85 232.41)
		)
		(stroke
			(width 0)
			(type default)
		)
	)
	(wire
		(pts
			(xy 227.33 54.61) (xy 260.35 54.61)
		)
		(stroke
			(width 0)
			(type default)
		)
	)
	(wire
		(pts
			(xy 267.97 171.45) (xy 273.05 171.45)
		)
		(stroke
			(width 0)
			(type default)
		)
	)
	(wire
		(pts
			(xy 179.07 222.25) (xy 201.93 222.25)
		)
		(stroke
			(width 0)
			(type default)
		)
	)
	(wire
		(pts
			(xy 171.45 110.49) (xy 171.45 118.11)
		)
		(stroke
			(width 0)
			(type default)
		)
	)
	(wire
		(pts
			(xy 231.14 199.39) (xy 227.33 199.39)
		)
		(stroke
			(width 0)
			(type default)
		)
	)
	(wire
		(pts
			(xy 173.99 201.93) (xy 165.1 201.93)
		)
		(stroke
			(width 0)
			(type default)
		)
	)
	(wire
		(pts
			(xy 198.12 85.09) (xy 201.93 85.09)
		)
		(stroke
			(width 0)
			(type default)
		)
	)
	(wire
		(pts
			(xy 252.73 102.87) (xy 227.33 102.87)
		)
		(stroke
			(width 0)
			(type default)
		)
	)
	(polyline
		(pts
			(xy 295.91 234.95) (xy 260.35 234.95)
		)
		(stroke
			(width 0)
			(type dash)
		)
	)
	(wire
		(pts
			(xy 252.73 120.65) (xy 227.33 120.65)
		)
		(stroke
			(width 0)
			(type default)
		)
	)
	(wire
		(pts
			(xy 248.92 212.09) (xy 248.92 219.71)
		)
		(stroke
			(width 0)
			(type default)
		)
	)
	(wire
		(pts
			(xy 171.45 234.95) (xy 171.45 242.57)
		)
		(stroke
			(width 0)
			(type default)
		)
	)
	(wire
		(pts
			(xy 231.14 80.01) (xy 227.33 80.01)
		)
		(stroke
			(width 0)
			(type default)
		)
	)
	(polyline
		(pts
			(xy 260.35 227.33) (xy 295.91 227.33)
		)
		(stroke
			(width 0)
			(type dash)
		)
	)
	(wire
		(pts
			(xy 252.73 179.07) (xy 252.73 180.34)
		)
		(stroke
			(width 0)
			(type default)
		)
	)
	(wire
		(pts
			(xy 179.07 214.63) (xy 201.93 214.63)
		)
		(stroke
			(width 0)
			(type default)
		)
	)
	(wire
		(pts
			(xy 257.81 212.09) (xy 257.81 213.36)
		)
		(stroke
			(width 0)
			(type default)
		)
	)
	(wire
		(pts
			(xy 231.14 82.55) (xy 227.33 82.55)
		)
		(stroke
			(width 0)
			(type default)
		)
	)
	(wire
		(pts
			(xy 147.32 57.15) (xy 144.78 57.15)
		)
		(stroke
			(width 0)
			(type default)
		)
	)
	(wire
		(pts
			(xy 166.37 72.39) (xy 171.45 72.39)
		)
		(stroke
			(width 0)
			(type default)
		)
	)
	(wire
		(pts
			(xy 198.12 143.51) (xy 201.93 143.51)
		)
		(stroke
			(width 0)
			(type default)
		)
	)
	(wire
		(pts
			(xy 171.45 133.35) (xy 201.93 133.35)
		)
		(stroke
			(width 0)
			(type default)
		)
	)
	(wire
		(pts
			(xy 176.53 189.23) (xy 201.93 189.23)
		)
		(stroke
			(width 0)
			(type default)
		)
	)
	(wire
		(pts
			(xy 227.33 128.27) (xy 231.14 128.27)
		)
		(stroke
			(width 0)
			(type default)
		)
	)
	(wire
		(pts
			(xy 201.93 115.57) (xy 198.12 115.57)
		)
		(stroke
			(width 0)
			(type default)
		)
	)
	(wire
		(pts
			(xy 171.45 44.45) (xy 171.45 45.72)
		)
		(stroke
			(width 0)
			(type default)
		)
	)
	(wire
		(pts
			(xy 171.45 118.11) (xy 171.45 125.73)
		)
		(stroke
			(width 0)
			(type default)
		)
	)
	(wire
		(pts
			(xy 198.12 161.29) (xy 201.93 161.29)
		)
		(stroke
			(width 0)
			(type default)
		)
	)
	(wire
		(pts
			(xy 231.14 156.21) (xy 227.33 156.21)
		)
		(stroke
			(width 0)
			(type default)
		)
	)
	(wire
		(pts
			(xy 227.33 92.71) (xy 231.14 92.71)
		)
		(stroke
			(width 0)
			(type default)
		)
	)
	(wire
		(pts
			(xy 201.93 41.91) (xy 199.39 41.91)
		)
		(stroke
			(width 0)
			(type default)
		)
	)
	(polyline
		(pts
			(xy 260.35 227.33) (xy 260.35 234.95)
		)
		(stroke
			(width 0)
			(type dash)
		)
	)
	(wire
		(pts
			(xy 198.12 237.49) (xy 201.93 237.49)
		)
		(stroke
			(width 0)
			(type default)
		)
	)
	(wire
		(pts
			(xy 231.14 222.25) (xy 227.33 222.25)
		)
		(stroke
			(width 0)
			(type default)
		)
	)
	(wire
		(pts
			(xy 172.72 69.85) (xy 172.72 64.77)
		)
		(stroke
			(width 0)
			(type default)
		)
	)
	(polyline
		(pts
			(xy 295.91 168.91) (xy 295.91 176.53)
		)
		(stroke
			(width 0)
			(type dash)
		)
	)
	(wire
		(pts
			(xy 231.14 196.85) (xy 227.33 196.85)
		)
		(stroke
			(width 0)
			(type default)
		)
	)
	(wire
		(pts
			(xy 242.57 39.37) (xy 229.87 39.37)
		)
		(stroke
			(width 0)
			(type default)
		)
	)
	(wire
		(pts
			(xy 173.99 219.71) (xy 165.1 219.71)
		)
		(stroke
			(width 0)
			(type default)
		)
	)
	(wire
		(pts
			(xy 257.81 242.57) (xy 227.33 242.57)
		)
		(stroke
			(width 0)
			(type default)
		)
	)
	(wire
		(pts
			(xy 171.45 257.81) (xy 201.93 257.81)
		)
		(stroke
			(width 0)
			(type default)
		)
	)
	(wire
		(pts
			(xy 227.33 184.15) (xy 231.14 184.15)
		)
		(stroke
			(width 0)
			(type default)
		)
	)
	(wire
		(pts
			(xy 287.02 69.85) (xy 271.78 69.85)
		)
		(stroke
			(width 0)
			(type default)
		)
	)
	(wire
		(pts
			(xy 201.93 62.23) (xy 187.96 62.23)
		)
		(stroke
			(width 0)
			(type default)
		)
	)
	(wire
		(pts
			(xy 262.89 171.45) (xy 267.97 171.45)
		)
		(stroke
			(width 0)
			(type default)
		)
	)
	(wire
		(pts
			(xy 201.93 113.03) (xy 198.12 113.03)
		)
		(stroke
			(width 0)
			(type default)
		)
	)
	(wire
		(pts
			(xy 227.33 209.55) (xy 231.14 209.55)
		)
		(stroke
			(width 0)
			(type default)
		)
	)
	(wire
		(pts
			(xy 231.14 163.83) (xy 227.33 163.83)
		)
		(stroke
			(width 0)
			(type default)
		)
	)
	(wire
		(pts
			(xy 201.93 128.27) (xy 198.12 128.27)
		)
		(stroke
			(width 0)
			(type default)
		)
	)
	(wire
		(pts
			(xy 201.93 240.03) (xy 198.12 240.03)
		)
		(stroke
			(width 0)
			(type default)
		)
	)
	(wire
		(pts
			(xy 227.33 252.73) (xy 231.14 252.73)
		)
		(stroke
			(width 0)
			(type default)
		)
	)
	(wire
		(pts
			(xy 201.93 120.65) (xy 198.12 120.65)
		)
		(stroke
			(width 0)
			(type default)
		)
	)
	(wire
		(pts
			(xy 257.81 265.43) (xy 227.33 265.43)
		)
		(stroke
			(width 0)
			(type default)
		)
	)
	(wire
		(pts
			(xy 201.93 105.41) (xy 198.12 105.41)
		)
		(stroke
			(width 0)
			(type default)
		)
	)
	(wire
		(pts
			(xy 231.14 133.35) (xy 227.33 133.35)
		)
		(stroke
			(width 0)
			(type default)
		)
	)
	(wire
		(pts
			(xy 274.32 72.39) (xy 287.02 72.39)
		)
		(stroke
			(width 0)
			(type default)
		)
	)
	(wire
		(pts
			(xy 227.33 44.45) (xy 248.92 44.45)
		)
		(stroke
			(width 0)
			(type default)
		)
	)
	(wire
		(pts
			(xy 257.81 250.19) (xy 257.81 257.81)
		)
		(stroke
			(width 0)
			(type default)
		)
	)
	(wire
		(pts
			(xy 227.33 237.49) (xy 231.14 237.49)
		)
		(stroke
			(width 0)
			(type default)
		)
	)
	(wire
		(pts
			(xy 201.93 247.65) (xy 198.12 247.65)
		)
		(stroke
			(width 0)
			(type default)
		)
	)
	(wire
		(pts
			(xy 231.14 115.57) (xy 227.33 115.57)
		)
		(stroke
			(width 0)
			(type default)
		)
	)
	(wire
		(pts
			(xy 165.1 207.01) (xy 173.99 207.01)
		)
		(stroke
			(width 0)
			(type default)
		)
	)
	(wire
		(pts
			(xy 173.99 212.09) (xy 165.1 212.09)
		)
		(stroke
			(width 0)
			(type default)
		)
	)
	(wire
		(pts
			(xy 171.45 125.73) (xy 171.45 133.35)
		)
		(stroke
			(width 0)
			(type default)
		)
	)
	(wire
		(pts
			(xy 257.81 234.95) (xy 227.33 234.95)
		)
		(stroke
			(width 0)
			(type default)
		)
	)
	(wire
		(pts
			(xy 179.07 212.09) (xy 201.93 212.09)
		)
		(stroke
			(width 0)
			(type default)
		)
	)
	(wire
		(pts
			(xy 227.33 64.77) (xy 266.7 64.77)
		)
		(stroke
			(width 0)
			(type default)
		)
	)
	(wire
		(pts
			(xy 171.45 257.81) (xy 171.45 265.43)
		)
		(stroke
			(width 0)
			(type default)
		)
	)
	(wire
		(pts
			(xy 198.12 92.71) (xy 201.93 92.71)
		)
		(stroke
			(width 0)
			(type default)
		)
	)
	(wire
		(pts
			(xy 300.99 55.88) (xy 269.24 55.88)
		)
		(stroke
			(width 0)
			(type default)
		)
	)
	(wire
		(pts
			(xy 179.07 199.39) (xy 201.93 199.39)
		)
		(stroke
			(width 0)
			(type default)
		)
	)
	(wire
		(pts
			(xy 186.69 39.37) (xy 199.39 39.37)
		)
		(stroke
			(width 0)
			(type default)
		)
	)
	(wire
		(pts
			(xy 171.45 250.19) (xy 201.93 250.19)
		)
		(stroke
			(width 0)
			(type default)
		)
	)
	(wire
		(pts
			(xy 171.45 185.42) (xy 171.45 186.69)
		)
		(stroke
			(width 0)
			(type default)
		)
	)
	(wire
		(pts
			(xy 300.99 53.34) (xy 266.7 53.34)
		)
		(stroke
			(width 0)
			(type default)
		)
	)
	(wire
		(pts
			(xy 227.33 52.07) (xy 241.3 52.07)
		)
		(stroke
			(width 0)
			(type default)
		)
	)
	(wire
		(pts
			(xy 227.33 135.89) (xy 231.14 135.89)
		)
		(stroke
			(width 0)
			(type default)
		)
	)
	(wire
		(pts
			(xy 179.07 229.87) (xy 201.93 229.87)
		)
		(stroke
			(width 0)
			(type default)
		)
	)
	(wire
		(pts
			(xy 173.99 199.39) (xy 165.1 199.39)
		)
		(stroke
			(width 0)
			(type default)
		)
	)
	(wire
		(pts
			(xy 201.93 158.75) (xy 198.12 158.75)
		)
		(stroke
			(width 0)
			(type default)
		)
	)
	(wire
		(pts
			(xy 252.73 120.65) (xy 252.73 121.92)
		)
		(stroke
			(width 0)
			(type default)
		)
	)
	(wire
		(pts
			(xy 269.24 229.87) (xy 227.33 229.87)
		)
		(stroke
			(width 0)
			(type default)
		)
	)
	(wire
		(pts
			(xy 176.53 189.23) (xy 176.53 185.42)
		)
		(stroke
			(width 0)
			(type default)
		)
	)
	(wire
		(pts
			(xy 227.33 67.31) (xy 269.24 67.31)
		)
		(stroke
			(width 0)
			(type default)
		)
	)
	(wire
		(pts
			(xy 257.81 265.43) (xy 257.81 266.7)
		)
		(stroke
			(width 0)
			(type default)
		)
	)
	(wire
		(pts
			(xy 201.93 97.79) (xy 198.12 97.79)
		)
		(stroke
			(width 0)
			(type default)
		)
	)
	(wire
		(pts
			(xy 165.1 229.87) (xy 173.99 229.87)
		)
		(stroke
			(width 0)
			(type default)
		)
	)
	(wire
		(pts
			(xy 187.96 67.31) (xy 201.93 67.31)
		)
		(stroke
			(width 0)
			(type default)
		)
	)
	(wire
		(pts
			(xy 300.99 58.42) (xy 271.78 58.42)
		)
		(stroke
			(width 0)
			(type default)
		)
	)
	(wire
		(pts
			(xy 227.33 59.69) (xy 241.3 59.69)
		)
		(stroke
			(width 0)
			(type default)
		)
	)
	(wire
		(pts
			(xy 231.14 95.25) (xy 227.33 95.25)
		)
		(stroke
			(width 0)
			(type default)
		)
	)
	(wire
		(pts
			(xy 201.93 87.63) (xy 198.12 87.63)
		)
		(stroke
			(width 0)
			(type default)
		)
	)
	(wire
		(pts
			(xy 231.14 247.65) (xy 227.33 247.65)
		)
		(stroke
			(width 0)
			(type default)
		)
	)
	(wire
		(pts
			(xy 231.14 173.99) (xy 227.33 173.99)
		)
		(stroke
			(width 0)
			(type default)
		)
	)
	(wire
		(pts
			(xy 227.33 224.79) (xy 231.14 224.79)
		)
		(stroke
			(width 0)
			(type default)
		)
	)
	(wire
		(pts
			(xy 201.93 64.77) (xy 187.96 64.77)
		)
		(stroke
			(width 0)
			(type default)
		)
	)
	(wire
		(pts
			(xy 199.39 46.99) (xy 199.39 44.45)
		)
		(stroke
			(width 0)
			(type default)
		)
	)
	(wire
		(pts
			(xy 179.07 227.33) (xy 201.93 227.33)
		)
		(stroke
			(width 0)
			(type default)
		)
	)
	(wire
		(pts
			(xy 179.07 204.47) (xy 201.93 204.47)
		)
		(stroke
			(width 0)
			(type default)
		)
	)
	(wire
		(pts
			(xy 171.45 265.43) (xy 171.45 266.7)
		)
		(stroke
			(width 0)
			(type default)
		)
	)
	(wire
		(pts
			(xy 257.81 257.81) (xy 257.81 265.43)
		)
		(stroke
			(width 0)
			(type default)
		)
	)
	(wire
		(pts
			(xy 165.1 196.85) (xy 173.99 196.85)
		)
		(stroke
			(width 0)
			(type default)
		)
	)
	(wire
		(pts
			(xy 144.78 59.69) (xy 147.32 59.69)
		)
		(stroke
			(width 0)
			(type default)
		)
	)
	(wire
		(pts
			(xy 271.78 58.42) (xy 271.78 69.85)
		)
		(stroke
			(width 0)
			(type default)
		)
	)
	(wire
		(pts
			(xy 165.1 227.33) (xy 173.99 227.33)
		)
		(stroke
			(width 0)
			(type default)
		)
	)
	(wire
		(pts
			(xy 231.14 255.27) (xy 227.33 255.27)
		)
		(stroke
			(width 0)
			(type default)
		)
	)
	(wire
		(pts
			(xy 201.93 171.45) (xy 198.12 171.45)
		)
		(stroke
			(width 0)
			(type default)
		)
	)
	(wire
		(pts
			(xy 300.99 69.85) (xy 292.1 69.85)
		)
		(stroke
			(width 0)
			(type default)
		)
	)
	(polyline
		(pts
			(xy 295.91 168.91) (xy 251.46 168.91)
		)
		(stroke
			(width 0)
			(type dash)
		)
	)
	(wire
		(pts
			(xy 171.45 265.43) (xy 201.93 265.43)
		)
		(stroke
			(width 0)
			(type default)
		)
	)
	(wire
		(pts
			(xy 227.33 245.11) (xy 231.14 245.11)
		)
		(stroke
			(width 0)
			(type default)
		)
	)
	(wire
		(pts
			(xy 257.81 242.57) (xy 257.81 250.19)
		)
		(stroke
			(width 0)
			(type default)
		)
	)
	(wire
		(pts
			(xy 179.07 217.17) (xy 201.93 217.17)
		)
		(stroke
			(width 0)
			(type default)
		)
	)
	(wire
		(pts
			(xy 199.39 39.37) (xy 201.93 39.37)
		)
		(stroke
			(width 0)
			(type default)
		)
	)
	(wire
		(pts
			(xy 227.33 41.91) (xy 229.87 41.91)
		)
		(stroke
			(width 0)
			(type default)
		)
	)
	(wire
		(pts
			(xy 227.33 146.05) (xy 231.14 146.05)
		)
		(stroke
			(width 0)
			(type default)
		)
	)
	(wire
		(pts
			(xy 274.32 60.96) (xy 274.32 72.39)
		)
		(stroke
			(width 0)
			(type default)
		)
	)
	(polyline
		(pts
			(xy 251.46 168.91) (xy 251.46 176.53)
		)
		(stroke
			(width 0)
			(type dash)
		)
	)
	(polyline
		(pts
			(xy 255.27 97.79) (xy 255.27 102.87)
		)
		(stroke
			(width 0)
			(type dash)
		)
	)
	(wire
		(pts
			(xy 231.14 262.89) (xy 227.33 262.89)
		)
		(stroke
			(width 0)
			(type default)
		)
	)
	(wire
		(pts
			(xy 201.93 262.89) (xy 198.12 262.89)
		)
		(stroke
			(width 0)
			(type default)
		)
	)
	(wire
		(pts
			(xy 227.33 168.91) (xy 231.14 168.91)
		)
		(stroke
			(width 0)
			(type default)
		)
	)
	(wire
		(pts
			(xy 231.14 204.47) (xy 227.33 204.47)
		)
		(stroke
			(width 0)
			(type default)
		)
	)
	(wire
		(pts
			(xy 201.93 255.27) (xy 198.12 255.27)
		)
		(stroke
			(width 0)
			(type default)
		)
	)
	(wire
		(pts
			(xy 171.45 242.57) (xy 201.93 242.57)
		)
		(stroke
			(width 0)
			(type default)
		)
	)
	(wire
		(pts
			(xy 231.14 110.49) (xy 227.33 110.49)
		)
		(stroke
			(width 0)
			(type default)
		)
	)
	(wire
		(pts
			(xy 257.81 257.81) (xy 227.33 257.81)
		)
		(stroke
			(width 0)
			(type default)
		)
	)
	(wire
		(pts
			(xy 172.72 64.77) (xy 168.91 64.77)
		)
		(stroke
			(width 0)
			(type default)
		)
	)
	(wire
		(pts
			(xy 199.39 41.91) (xy 199.39 39.37)
		)
		(stroke
			(width 0)
			(type default)
		)
	)
	(wire
		(pts
			(xy 227.33 85.09) (xy 231.14 85.09)
		)
		(stroke
			(width 0)
			(type default)
		)
	)
	(wire
		(pts
			(xy 172.72 69.85) (xy 201.93 69.85)
		)
		(stroke
			(width 0)
			(type default)
		)
	)
	(wire
		(pts
			(xy 260.35 54.61) (xy 260.35 62.23)
		)
		(stroke
			(width 0)
			(type default)
		)
	)
	(wire
		(pts
			(xy 231.14 138.43) (xy 227.33 138.43)
		)
		(stroke
			(width 0)
			(type default)
		)
	)
	(wire
		(pts
			(xy 201.93 146.05) (xy 198.12 146.05)
		)
		(stroke
			(width 0)
			(type default)
		)
	)
	(wire
		(pts
			(xy 173.99 224.79) (xy 165.1 224.79)
		)
		(stroke
			(width 0)
			(type default)
		)
	)
	(wire
		(pts
			(xy 227.33 176.53) (xy 231.14 176.53)
		)
		(stroke
			(width 0)
			(type default)
		)
	)
	(wire
		(pts
			(xy 257.81 234.95) (xy 257.81 242.57)
		)
		(stroke
			(width 0)
			(type default)
		)
	)
	(wire
		(pts
			(xy 252.73 143.51) (xy 252.73 144.78)
		)
		(stroke
			(width 0)
			(type default)
		)
	)
	(wire
		(pts
			(xy 201.93 173.99) (xy 198.12 173.99)
		)
		(stroke
			(width 0)
			(type default)
		)
	)
	(wire
		(pts
			(xy 231.14 118.11) (xy 227.33 118.11)
		)
		(stroke
			(width 0)
			(type default)
		)
	)
	(wire
		(pts
			(xy 198.12 245.11) (xy 201.93 245.11)
		)
		(stroke
			(width 0)
			(type default)
		)
	)
	(wire
		(pts
			(xy 201.93 163.83) (xy 198.12 163.83)
		)
		(stroke
			(width 0)
			(type default)
		)
	)
	(wire
		(pts
			(xy 264.16 44.45) (xy 254 44.45)
		)
		(stroke
			(width 0)
			(type default)
		)
	)
	(wire
		(pts
			(xy 179.07 219.71) (xy 201.93 219.71)
		)
		(stroke
			(width 0)
			(type default)
		)
	)
	(wire
		(pts
			(xy 231.14 189.23) (xy 227.33 189.23)
		)
		(stroke
			(width 0)
			(type default)
		)
	)
	(wire
		(pts
			(xy 252.73 102.87) (xy 252.73 104.14)
		)
		(stroke
			(width 0)
			(type default)
		)
	)
	(wire
		(pts
			(xy 227.33 148.59) (xy 231.14 148.59)
		)
		(stroke
			(width 0)
			(type default)
		)
	)
	(wire
		(pts
			(xy 201.93 179.07) (xy 198.12 179.07)
		)
		(stroke
			(width 0)
			(type default)
		)
	)
	(wire
		(pts
			(xy 198.12 260.35) (xy 201.93 260.35)
		)
		(stroke
			(width 0)
			(type default)
		)
	)
	(wire
		(pts
			(xy 231.14 181.61) (xy 227.33 181.61)
		)
		(stroke
			(width 0)
			(type default)
		)
	)
	(wire
		(pts
			(xy 227.33 107.95) (xy 231.14 107.95)
		)
		(stroke
			(width 0)
			(type default)
		)
	)
	(wire
		(pts
			(xy 198.12 252.73) (xy 201.93 252.73)
		)
		(stroke
			(width 0)
			(type default)
		)
	)
	(wire
		(pts
			(xy 171.45 234.95) (xy 201.93 234.95)
		)
		(stroke
			(width 0)
			(type default)
		)
	)
	(wire
		(pts
			(xy 260.35 62.23) (xy 227.33 62.23)
		)
		(stroke
			(width 0)
			(type default)
		)
	)
	(wire
		(pts
			(xy 227.33 158.75) (xy 231.14 158.75)
		)
		(stroke
			(width 0)
			(type default)
		)
	)
	(wire
		(pts
			(xy 201.93 46.99) (xy 199.39 46.99)
		)
		(stroke
			(width 0)
			(type default)
		)
	)
	(wire
		(pts
			(xy 231.14 214.63) (xy 227.33 214.63)
		)
		(stroke
			(width 0)
			(type default)
		)
	)
	(polyline
		(pts
			(xy 295.91 227.33) (xy 295.91 234.95)
		)
		(stroke
			(width 0)
			(type dash)
		)
	)
	(wire
		(pts
			(xy 201.93 123.19) (xy 198.12 123.19)
		)
		(stroke
			(width 0)
			(type default)
		)
	)
	(wire
		(pts
			(xy 246.38 166.37) (xy 246.38 158.75)
		)
		(stroke
			(width 0)
			(type default)
		)
	)
	(wire
		(pts
			(xy 300.99 64.77) (xy 292.1 64.77)
		)
		(stroke
			(width 0)
			(type default)
		)
	)
	(wire
		(pts
			(xy 179.07 207.01) (xy 201.93 207.01)
		)
		(stroke
			(width 0)
			(type default)
		)
	)
	(wire
		(pts
			(xy 198.12 168.91) (xy 201.93 168.91)
		)
		(stroke
			(width 0)
			(type default)
		)
	)
	(wire
		(pts
			(xy 198.12 176.53) (xy 201.93 176.53)
		)
		(stroke
			(width 0)
			(type default)
		)
	)
	(wire
		(pts
			(xy 266.7 53.34) (xy 266.7 64.77)
		)
		(stroke
			(width 0)
			(type default)
		)
	)
	(wire
		(pts
			(xy 201.93 156.21) (xy 198.12 156.21)
		)
		(stroke
			(width 0)
			(type default)
		)
	)
	(wire
		(pts
			(xy 227.33 260.35) (xy 231.14 260.35)
		)
		(stroke
			(width 0)
			(type default)
		)
	)
	(wire
		(pts
			(xy 231.14 113.03) (xy 227.33 113.03)
		)
		(stroke
			(width 0)
			(type default)
		)
	)
	(wire
		(pts
			(xy 231.14 207.01) (xy 227.33 207.01)
		)
		(stroke
			(width 0)
			(type default)
		)
	)
	(wire
		(pts
			(xy 300.99 72.39) (xy 292.1 72.39)
		)
		(stroke
			(width 0)
			(type default)
		)
	)
	(wire
		(pts
			(xy 252.73 143.51) (xy 227.33 143.51)
		)
		(stroke
			(width 0)
			(type default)
		)
	)
	(wire
		(pts
			(xy 171.45 125.73) (xy 201.93 125.73)
		)
		(stroke
			(width 0)
			(type default)
		)
	)
	(wire
		(pts
			(xy 201.93 140.97) (xy 198.12 140.97)
		)
		(stroke
			(width 0)
			(type default)
		)
	)
	(wire
		(pts
			(xy 179.07 196.85) (xy 201.93 196.85)
		)
		(stroke
			(width 0)
			(type default)
		)
	)
	(wire
		(pts
			(xy 264.16 100.33) (xy 227.33 100.33)
		)
		(stroke
			(width 0)
			(type default)
		)
	)
	(wire
		(pts
			(xy 198.12 107.95) (xy 201.93 107.95)
		)
		(stroke
			(width 0)
			(type default)
		)
	)
	(wire
		(pts
			(xy 227.33 46.99) (xy 260.35 46.99)
		)
		(stroke
			(width 0)
			(type default)
		)
	)
	(wire
		(pts
			(xy 171.45 110.49) (xy 201.93 110.49)
		)
		(stroke
			(width 0)
			(type default)
		)
	)
	(wire
		(pts
			(xy 201.93 138.43) (xy 198.12 138.43)
		)
		(stroke
			(width 0)
			(type default)
		)
	)
	(wire
		(pts
			(xy 231.14 97.79) (xy 227.33 97.79)
		)
		(stroke
			(width 0)
			(type default)
		)
	)
	(wire
		(pts
			(xy 231.14 240.03) (xy 227.33 240.03)
		)
		(stroke
			(width 0)
			(type default)
		)
	)
	(wire
		(pts
			(xy 176.53 185.42) (xy 171.45 185.42)
		)
		(stroke
			(width 0)
			(type default)
		)
	)
	(wire
		(pts
			(xy 201.93 102.87) (xy 198.12 102.87)
		)
		(stroke
			(width 0)
			(type default)
		)
	)
	(wire
		(pts
			(xy 231.14 186.69) (xy 227.33 186.69)
		)
		(stroke
			(width 0)
			(type default)
		)
	)
	(polyline
		(pts
			(xy 292.1 97.79) (xy 255.27 97.79)
		)
		(stroke
			(width 0)
			(type dash)
		)
	)
	(wire
		(pts
			(xy 229.87 39.37) (xy 227.33 39.37)
		)
		(stroke
			(width 0)
			(type default)
		)
	)
	(wire
		(pts
			(xy 248.92 219.71) (xy 227.33 219.71)
		)
		(stroke
			(width 0)
			(type default)
		)
	)
	(wire
		(pts
			(xy 171.45 118.11) (xy 201.93 118.11)
		)
		(stroke
			(width 0)
			(type default)
		)
	)
	(wire
		(pts
			(xy 231.14 123.19) (xy 227.33 123.19)
		)
		(stroke
			(width 0)
			(type default)
		)
	)
	(polyline
		(pts
			(xy 292.1 102.87) (xy 255.27 102.87)
		)
		(stroke
			(width 0)
			(type dash)
		)
	)
	(wire
		(pts
			(xy 198.12 184.15) (xy 201.93 184.15)
		)
		(stroke
			(width 0)
			(type default)
		)
	)
	(wire
		(pts
			(xy 171.45 166.37) (xy 201.93 166.37)
		)
		(stroke
			(width 0)
			(type default)
		)
	)
	(wire
		(pts
			(xy 269.24 55.88) (xy 269.24 67.31)
		)
		(stroke
			(width 0)
			(type default)
		)
	)
	(wire
		(pts
			(xy 176.53 72.39) (xy 201.93 72.39)
		)
		(stroke
			(width 0)
			(type default)
		)
	)
	(wire
		(pts
			(xy 257.81 250.19) (xy 227.33 250.19)
		)
		(stroke
			(width 0)
			(type default)
		)
	)
	(wire
		(pts
			(xy 179.07 224.79) (xy 201.93 224.79)
		)
		(stroke
			(width 0)
			(type default)
		)
	)
	(wire
		(pts
			(xy 260.35 46.99) (xy 262.89 46.99)
		)
		(stroke
			(width 0)
			(type default)
		)
	)
	(wire
		(pts
			(xy 227.33 69.85) (xy 271.78 69.85)
		)
		(stroke
			(width 0)
			(type default)
		)
	)
	(wire
		(pts
			(xy 252.73 179.07) (xy 227.33 179.07)
		)
		(stroke
			(width 0)
			(type default)
		)
	)
	(wire
		(pts
			(xy 171.45 166.37) (xy 171.45 167.64)
		)
		(stroke
			(width 0)
			(type default)
		)
	)
	(wire
		(pts
			(xy 227.33 227.33) (xy 248.92 227.33)
		)
		(stroke
			(width 0)
			(type default)
		)
	)
	(wire
		(pts
			(xy 171.45 250.19) (xy 171.45 257.81)
		)
		(stroke
			(width 0)
			(type default)
		)
	)
	(wire
		(pts
			(xy 201.93 54.61) (xy 187.96 54.61)
		)
		(stroke
			(width 0)
			(type default)
		)
	)
	(wire
		(pts
			(xy 300.99 60.96) (xy 274.32 60.96)
		)
		(stroke
			(width 0)
			(type default)
		)
	)
	(wire
		(pts
			(xy 179.07 201.93) (xy 201.93 201.93)
		)
		(stroke
			(width 0)
			(type default)
		)
	)
	(wire
		(pts
			(xy 248.92 219.71) (xy 248.92 227.33)
		)
		(stroke
			(width 0)
			(type default)
		)
	)
	(wire
		(pts
			(xy 171.45 44.45) (xy 199.39 44.45)
		)
		(stroke
			(width 0)
			(type default)
		)
	)
	(wire
		(pts
			(xy 201.93 82.55) (xy 198.12 82.55)
		)
		(stroke
			(width 0)
			(type default)
		)
	)
	(wire
		(pts
			(xy 201.93 80.01) (xy 198.12 80.01)
		)
		(stroke
			(width 0)
			(type default)
		)
	)
	(wire
		(pts
			(xy 231.14 90.17) (xy 227.33 90.17)
		)
		(stroke
			(width 0)
			(type default)
		)
	)
	(wire
		(pts
			(xy 231.14 130.81) (xy 227.33 130.81)
		)
		(stroke
			(width 0)
			(type default)
		)
	)
	(wire
		(pts
			(xy 201.93 57.15) (xy 187.96 57.15)
		)
		(stroke
			(width 0)
			(type default)
		)
	)
	(wire
		(pts
			(xy 227.33 201.93) (xy 231.14 201.93)
		)
		(stroke
			(width 0)
			(type default)
		)
	)
	(wire
		(pts
			(xy 252.73 158.75) (xy 252.73 160.02)
		)
		(stroke
			(width 0)
			(type default)
		)
	)
	(wire
		(pts
			(xy 227.33 217.17) (xy 231.14 217.17)
		)
		(stroke
			(width 0)
			(type default)
		)
	)
	(wire
		(pts
			(xy 269.24 67.31) (xy 287.02 67.31)
		)
		(stroke
			(width 0)
			(type default)
		)
	)
	(wire
		(pts
			(xy 267.97 173.99) (xy 267.97 171.45)
		)
		(stroke
			(width 0)
			(type default)
		)
	)
	(wire
		(pts
			(xy 198.12 100.33) (xy 201.93 100.33)
		)
		(stroke
			(width 0)
			(type default)
		)
	)
	(wire
		(pts
			(xy 201.93 90.17) (xy 198.12 90.17)
		)
		(stroke
			(width 0)
			(type default)
		)
	)
	(wire
		(pts
			(xy 173.99 214.63) (xy 165.1 214.63)
		)
		(stroke
			(width 0)
			(type default)
		)
	)
	(wire
		(pts
			(xy 262.89 46.99) (xy 262.89 48.26)
		)
		(stroke
			(width 0)
			(type default)
		)
	)
	(wire
		(pts
			(xy 248.92 212.09) (xy 227.33 212.09)
		)
		(stroke
			(width 0)
			(type default)
		)
	)
	(wire
		(pts
			(xy 171.45 242.57) (xy 171.45 250.19)
		)
		(stroke
			(width 0)
			(type default)
		)
	)
	(wire
		(pts
			(xy 165.1 204.47) (xy 173.99 204.47)
		)
		(stroke
			(width 0)
			(type default)
		)
	)
	(wire
		(pts
			(xy 165.1 217.17) (xy 173.99 217.17)
		)
		(stroke
			(width 0)
			(type default)
		)
	)
	(wire
		(pts
			(xy 246.38 166.37) (xy 227.33 166.37)
		)
		(stroke
			(width 0)
			(type default)
		)
	)
	(wire
		(pts
			(xy 227.33 161.29) (xy 231.14 161.29)
		)
		(stroke
			(width 0)
			(type default)
		)
	)
	(wire
		(pts
			(xy 246.38 158.75) (xy 252.73 158.75)
		)
		(stroke
			(width 0)
			(type default)
		)
	)
	(wire
		(pts
			(xy 227.33 171.45) (xy 257.81 171.45)
		)
		(stroke
			(width 0)
			(type default)
		)
	)
	(wire
		(pts
			(xy 199.39 44.45) (xy 201.93 44.45)
		)
		(stroke
			(width 0)
			(type default)
		)
	)
	(wire
		(pts
			(xy 274.32 72.39) (xy 227.33 72.39)
		)
		(stroke
			(width 0)
			(type default)
		)
	)
	(wire
		(pts
			(xy 187.96 52.07) (xy 201.93 52.07)
		)
		(stroke
			(width 0)
			(type default)
		)
	)
	(wire
		(pts
			(xy 260.35 46.99) (xy 260.35 54.61)
		)
		(stroke
			(width 0)
			(type default)
		)
	)
	(wire
		(pts
			(xy 281.94 173.99) (xy 267.97 173.99)
		)
		(stroke
			(width 0)
			(type default)
		)
	)
	(polyline
		(pts
			(xy 292.1 97.79) (xy 292.1 102.87)
		)
		(stroke
			(width 0)
			(type dash)
		)
	)
	(wire
		(pts
			(xy 257.81 212.09) (xy 248.92 212.09)
		)
		(stroke
			(width 0)
			(type default)
		)
	)
	(wire
		(pts
			(xy 266.7 64.77) (xy 287.02 64.77)
		)
		(stroke
			(width 0)
			(type default)
		)
	)
	(wire
		(pts
			(xy 201.93 181.61) (xy 198.12 181.61)
		)
		(stroke
			(width 0)
			(type default)
		)
	)
	(wire
		(pts
			(xy 241.3 57.15) (xy 227.33 57.15)
		)
		(stroke
			(width 0)
			(type default)
		)
	)
	(wire
		(pts
			(xy 231.14 140.97) (xy 227.33 140.97)
		)
		(stroke
			(width 0)
			(type default)
		)
	)
	(wire
		(pts
			(xy 229.87 41.91) (xy 229.87 39.37)
		)
		(stroke
			(width 0)
			(type default)
		)
	)
	(wire
		(pts
			(xy 187.96 49.53) (xy 201.93 49.53)
		)
		(stroke
			(width 0)
			(type default)
		)
	)
	(wire
		(pts
			(xy 165.1 222.25) (xy 173.99 222.25)
		)
		(stroke
			(width 0)
			(type default)
		)
	)
	(wire
		(pts
			(xy 165.1 209.55) (xy 173.99 209.55)
		)
		(stroke
			(width 0)
			(type default)
		)
	)
	(wire
		(pts
			(xy 300.99 67.31) (xy 292.1 67.31)
		)
		(stroke
			(width 0)
			(type default)
		)
	)
	(wire
		(pts
			(xy 231.14 125.73) (xy 227.33 125.73)
		)
		(stroke
			(width 0)
			(type default)
		)
	)
	(wire
		(pts
			(xy 187.96 59.69) (xy 201.93 59.69)
		)
		(stroke
			(width 0)
			(type default)
		)
	)
	(wire
		(pts
			(xy 171.45 133.35) (xy 171.45 134.62)
		)
		(stroke
			(width 0)
			(type default)
		)
	)
	(polyline
		(pts
			(xy 295.91 176.53) (xy 251.46 176.53)
		)
		(stroke
			(width 0)
			(type dash)
		)
	)
	(wire
		(pts
			(xy 231.14 105.41) (xy 227.33 105.41)
		)
		(stroke
			(width 0)
			(type default)
		)
	)
	(wire
		(pts
			(xy 201.93 148.59) (xy 198.12 148.59)
		)
		(stroke
			(width 0)
			(type default)
		)
	)
	(wire
		(pts
			(xy 227.33 49.53) (xy 241.3 49.53)
		)
		(stroke
			(width 0)
			(type default)
		)
	)
	(wire
		(pts
			(xy 201.93 186.69) (xy 198.12 186.69)
		)
		(stroke
			(width 0)
			(type default)
		)
	)
	(wire
		(pts
			(xy 231.14 87.63) (xy 227.33 87.63)
		)
		(stroke
			(width 0)
			(type default)
		)
	)
	(wire
		(pts
			(xy 227.33 232.41) (xy 269.24 232.41)
		)
		(stroke
			(width 0)
			(type default)
		)
	)
	(wire
		(pts
			(xy 278.13 171.45) (xy 281.94 171.45)
		)
		(stroke
			(width 0)
			(type default)
		)
	)
	(wire
		(pts
			(xy 198.12 135.89) (xy 201.93 135.89)
		)
		(stroke
			(width 0)
			(type default)
		)
	)
	(label "SPARE0"
		(at 200.66 227.33 180)
		(effects
			(font
				(size 1.27 1.27)
			)
			(justify right bottom)
		)
	)
	(label "IRQ_N"
		(at 200.66 229.87 180)
		(effects
			(font
				(size 1.27 1.27)
			)
			(justify right bottom)
		)
	)
	(label "VIRTUAL_RESEAT"
		(at 199.39 72.39 180)
		(effects
			(font
				(size 1.27 1.27)
			)
			(justify right bottom)
		)
	)
	(label "CHASI#"
		(at 200.66 224.79 180)
		(effects
			(font
				(size 1.27 1.27)
			)
			(justify right bottom)
		)
	)
	(label "HPM_STBY_RST_N"
		(at 200.66 204.47 180)
		(effects
			(font
				(size 1.27 1.27)
			)
			(justify right bottom)
		)
	)
	(label "HPM_STBY_RDY"
		(at 200.66 199.39 180)
		(effects
			(font
				(size 1.27 1.27)
			)
			(justify right bottom)
		)
	)
	(label "HPM_FW_RECOVERY"
		(at 200.66 196.85 180)
		(effects
			(font
				(size 1.27 1.27)
			)
			(justify right bottom)
		)
	)
	(label "SPARE1"
		(at 200.66 219.71 180)
		(effects
			(font
				(size 1.27 1.27)
			)
			(justify right bottom)
		)
	)
	(label "RST_PLTRST_BUF_N"
		(at 200.66 217.17 180)
		(effects
			(font
				(size 1.27 1.27)
			)
			(justify right bottom)
		)
	)
	(label "SYS_PWRBTN_N"
		(at 200.66 207.01 180)
		(effects
			(font
				(size 1.27 1.27)
			)
			(justify right bottom)
		)
	)
	(label "HPM_STBY_EN"
		(at 200.66 201.93 180)
		(effects
			(font
				(size 1.27 1.27)
			)
			(justify right bottom)
		)
	)
	(label "SYS_PWROK"
		(at 200.66 209.55 180)
		(effects
			(font
				(size 1.27 1.27)
			)
			(justify right bottom)
		)
	)
	(label "PRSNT0_N"
		(at 231.14 44.45 0)
		(effects
			(font
				(size 1.27 1.27)
			)
			(justify left bottom)
		)
	)
	(label "RoT_CPU_RST_N"
		(at 200.66 222.25 180)
		(effects
			(font
				(size 1.27 1.27)
			)
			(justify right bottom)
		)
	)
	(label "DBP_PRDY_N"
		(at 200.66 214.63 180)
		(effects
			(font
				(size 1.27 1.27)
			)
			(justify right bottom)
		)
	)
	(label "DBP_PREQ_N"
		(at 200.66 212.09 180)
		(effects
			(font
				(size 1.27 1.27)
			)
			(justify right bottom)
		)
	)
	(global_label "SGPIO0_CLK"
		(shape input)
		(at 231.14 158.75 0)
		(fields_autoplaced yes)
		(effects
			(font
				(size 1.27 1.27)
			)
			(justify left)
		)
		(property "Intersheetrefs" "${INTERSHEET_REFS}"
			(at -0.635 0.635 0)
			(effects
				(font
					(size 1.27 1.27)
				)
				(justify right)
				(hide yes)
			)
		)
	)
	(global_label "I2C[2]_SDA"
		(shape input)
		(at 198.12 92.71 180)
		(fields_autoplaced yes)
		(effects
			(font
				(size 1.27 1.27)
			)
			(justify right)
		)
		(property "Intersheetrefs" "${INTERSHEET_REFS}"
			(at 29.845 0.635 0)
			(effects
				(font
					(size 1.27 1.27)
				)
				(hide yes)
			)
		)
	)
	(global_label "PCIE_HPM_TX[0]_P"
		(shape input)
		(at 231.14 237.49 0)
		(fields_autoplaced yes)
		(effects
			(font
				(size 1.27 1.27)
			)
			(justify left)
		)
		(property "Intersheetrefs" "${INTERSHEET_REFS}"
			(at -0.635 0.635 0)
			(effects
				(font
					(size 1.27 1.27)
				)
				(justify right)
				(hide yes)
			)
		)
	)
	(global_label "ESPI_IO3_1V8"
		(shape input)
		(at 231.14 97.79 0)
		(fields_autoplaced yes)
		(effects
			(font
				(size 1.27 1.27)
			)
			(justify left)
		)
		(property "Intersheetrefs" "${INTERSHEET_REFS}"
			(at -0.635 0.635 0)
			(effects
				(font
					(size 1.27 1.27)
				)
				(justify right)
				(hide yes)
			)
		)
	)
	(global_label "PRSNT1_N"
		(shape input)
		(at 196.85 232.41 180)
		(fields_autoplaced yes)
		(effects
			(font
				(size 1.27 1.27)
			)
			(justify right)
		)
		(property "Intersheetrefs" "${INTERSHEET_REFS}"
			(at 28.575 0.635 0)
			(effects
				(font
					(size 1.27 1.27)
				)
				(justify right)
				(hide yes)
			)
		)
	)
	(global_label "I3C[1]_SDA"
		(shape input)
		(at 187.96 57.15 180)
		(fields_autoplaced yes)
		(effects
			(font
				(size 1.27 1.27)
			)
			(justify right)
		)
		(property "Intersheetrefs" "${INTERSHEET_REFS}"
			(at 19.685 0.635 0)
			(effects
				(font
					(size 1.27 1.27)
				)
				(hide yes)
			)
		)
	)
	(global_label "PCIE_HPM_CLK_P"
		(shape input)
		(at 269.24 229.87 0)
		(fields_autoplaced yes)
		(effects
			(font
				(size 1.27 1.27)
			)
			(justify left)
		)
		(property "Intersheetrefs" "${INTERSHEET_REFS}"
			(at 37.465 0.635 0)
			(effects
				(font
					(size 1.27 1.27)
				)
				(justify right)
				(hide yes)
			)
		)
	)
	(global_label "PCIE_BMC_CLK_100_P"
		(shape input)
		(at 198.12 113.03 180)
		(fields_autoplaced yes)
		(effects
			(font
				(size 1.27 1.27)
			)
			(justify right)
		)
		(property "Intersheetrefs" "${INTERSHEET_REFS}"
			(at 29.845 0.635 0)
			(effects
				(font
					(size 1.27 1.27)
				)
				(hide yes)
			)
		)
	)
	(global_label "SGPIO0_CLK"
		(shape input)
		(at 281.94 171.45 0)
		(fields_autoplaced yes)
		(effects
			(font
				(size 1.27 1.27)
			)
			(justify left)
		)
		(property "Intersheetrefs" "${INTERSHEET_REFS}"
			(at 17.145 0.635 0)
			(effects
				(font
					(size 1.27 1.27)
				)
				(justify right)
				(hide yes)
			)
		)
	)
	(global_label "P12V_AUX"
		(shape input)
		(at 186.69 39.37 180)
		(fields_autoplaced yes)
		(effects
			(font
				(size 1.27 1.27)
			)
			(justify right)
		)
		(property "Intersheetrefs" "${INTERSHEET_REFS}"
			(at 18.415 0.635 0)
			(effects
				(font
					(size 1.27 1.27)
				)
				(hide yes)
			)
		)
	)
	(global_label "QSPI1_D3"
		(shape input)
		(at 231.14 209.55 0)
		(fields_autoplaced yes)
		(effects
			(font
				(size 1.27 1.27)
			)
			(justify left)
		)
		(property "Intersheetrefs" "${INTERSHEET_REFS}"
			(at -0.635 0.635 0)
			(effects
				(font
					(size 1.27 1.27)
				)
				(justify right)
				(hide yes)
			)
		)
	)
	(global_label "PECI_BMC"
		(shape input)
		(at 144.78 57.15 180)
		(fields_autoplaced yes)
		(effects
			(font
				(size 1.27 1.27)
			)
			(justify right)
		)
		(property "Intersheetrefs" "${INTERSHEET_REFS}"
			(at 403.225 -88.9 0)
			(effects
				(font
					(size 1.27 1.27)
				)
				(justify left)
				(hide yes)
			)
		)
	)
	(global_label "I2C[4]_SDA"
		(shape input)
		(at 198.12 102.87 180)
		(fields_autoplaced yes)
		(effects
			(font
				(size 1.27 1.27)
			)
			(justify right)
		)
		(property "Intersheetrefs" "${INTERSHEET_REFS}"
			(at 29.845 0.635 0)
			(effects
				(font
					(size 1.27 1.27)
				)
				(hide yes)
			)
		)
	)
	(global_label "NCSI_CLK"
		(shape input)
		(at 231.14 123.19 0)
		(fields_autoplaced yes)
		(effects
			(font
				(size 1.27 1.27)
			)
			(justify left)
		)
		(property "Intersheetrefs" "${INTERSHEET_REFS}"
			(at -0.635 0.635 0)
			(effects
				(font
					(size 1.27 1.27)
				)
				(justify right)
				(hide yes)
			)
		)
	)
	(global_label "I2C[3]_SDA"
		(shape input)
		(at 198.12 97.79 180)
		(fields_autoplaced yes)
		(effects
			(font
				(size 1.27 1.27)
			)
			(justify right)
		)
		(property "Intersheetrefs" "${INTERSHEET_REFS}"
			(at 29.845 0.635 0)
			(effects
				(font
					(size 1.27 1.27)
				)
				(hide yes)
			)
		)
	)
	(global_label "NCSI_RXD1"
		(shape input)
		(at 231.14 140.97 0)
		(fields_autoplaced yes)
		(effects
			(font
				(size 1.27 1.27)
			)
			(justify left)
		)
		(property "Intersheetrefs" "${INTERSHEET_REFS}"
			(at -0.635 0.635 0)
			(effects
				(font
					(size 1.27 1.27)
				)
				(justify right)
				(hide yes)
			)
		)
	)
	(global_label "I2C[11]_SDA"
		(shape input)
		(at 198.12 181.61 180)
		(fields_autoplaced yes)
		(effects
			(font
				(size 1.27 1.27)
			)
			(justify right)
		)
		(property "Intersheetrefs" "${INTERSHEET_REFS}"
			(at 29.845 0.635 0)
			(effects
				(font
					(size 1.27 1.27)
				)
				(hide yes)
			)
		)
	)
	(global_label "USB1_D_P"
		(shape input)
		(at 231.14 222.25 0)
		(fields_autoplaced yes)
		(effects
			(font
				(size 1.27 1.27)
			)
			(justify left)
		)
		(property "Intersheetrefs" "${INTERSHEET_REFS}"
			(at -0.635 0.635 0)
			(effects
				(font
					(size 1.27 1.27)
				)
				(justify right)
				(hide yes)
			)
		)
	)
	(global_label "HPM_FW_RECOVERY_R"
		(shape input)
		(at 165.1 196.85 180)
		(fields_autoplaced yes)
		(effects
			(font
				(size 1.27 1.27)
			)
			(justify right)
		)
		(property "Intersheetrefs" "${INTERSHEET_REFS}"
			(at 128.905 -16.51 0)
			(effects
				(font
					(size 1.27 1.27)
				)
				(justify right)
				(hide yes)
			)
		)
	)
	(global_label "I2C[9]_SDA"
		(shape input)
		(at 198.12 158.75 180)
		(fields_autoplaced yes)
		(effects
			(font
				(size 1.27 1.27)
			)
			(justify right)
		)
		(property "Intersheetrefs" "${INTERSHEET_REFS}"
			(at 29.845 0.635 0)
			(effects
				(font
					(size 1.27 1.27)
				)
				(hide yes)
			)
		)
	)
	(global_label "SGPIO_RESET_N"
		(shape input)
		(at 231.14 181.61 0)
		(fields_autoplaced yes)
		(effects
			(font
				(size 1.27 1.27)
			)
			(justify left)
		)
		(property "Intersheetrefs" "${INTERSHEET_REFS}"
			(at -0.635 0.635 0)
			(effects
				(font
					(size 1.27 1.27)
				)
				(justify right)
				(hide yes)
			)
		)
	)
	(global_label "JTAG_TCK"
		(shape input)
		(at 198.12 168.91 180)
		(fields_autoplaced yes)
		(effects
			(font
				(size 1.27 1.27)
			)
			(justify right)
		)
		(property "Intersheetrefs" "${INTERSHEET_REFS}"
			(at 29.845 0.635 0)
			(effects
				(font
					(size 1.27 1.27)
				)
				(hide yes)
			)
		)
	)
	(global_label "PVCCIO_PECI"
		(shape input)
		(at 231.14 148.59 0)
		(fields_autoplaced yes)
		(effects
			(font
				(size 1.27 1.27)
			)
			(justify left)
		)
		(property "Intersheetrefs" "${INTERSHEET_REFS}"
			(at -0.635 0.635 0)
			(effects
				(font
					(size 1.27 1.27)
				)
				(justify right)
				(hide yes)
			)
		)
	)
	(global_label "QSPI0_D2"
		(shape input)
		(at 231.14 115.57 0)
		(fields_autoplaced yes)
		(effects
			(font
				(size 1.27 1.27)
			)
			(justify left)
		)
		(property "Intersheetrefs" "${INTERSHEET_REFS}"
			(at -0.635 0.635 0)
			(effects
				(font
					(size 1.27 1.27)
				)
				(justify right)
				(hide yes)
			)
		)
	)
	(global_label "HPM_STBY_RST_N_R"
		(shape input)
		(at 165.1 204.47 180)
		(fields_autoplaced yes)
		(effects
			(font
				(size 1.27 1.27)
			)
			(justify right)
		)
		(property "Intersheetrefs" "${INTERSHEET_REFS}"
			(at 128.905 -13.97 0)
			(effects
				(font
					(size 1.27 1.27)
				)
				(justify right)
				(hide yes)
			)
		)
	)
	(global_label "I2C[0]_SDA"
		(shape input)
		(at 198.12 82.55 180)
		(fields_autoplaced yes)
		(effects
			(font
				(size 1.27 1.27)
			)
			(justify right)
		)
		(property "Intersheetrefs" "${INTERSHEET_REFS}"
			(at 29.845 0.635 0)
			(effects
				(font
					(size 1.27 1.27)
				)
				(hide yes)
			)
		)
	)
	(global_label "PCIE_HPM_RX[3]_P"
		(shape input)
		(at 198.12 260.35 180)
		(fields_autoplaced yes)
		(effects
			(font
				(size 1.27 1.27)
			)
			(justify right)
		)
		(property "Intersheetrefs" "${INTERSHEET_REFS}"
			(at 29.845 0.635 0)
			(effects
				(font
					(size 1.27 1.27)
				)
				(hide yes)
			)
		)
	)
	(global_label "I2C[0]_SCL"
		(shape input)
		(at 198.12 80.01 180)
		(fields_autoplaced yes)
		(effects
			(font
				(size 1.27 1.27)
			)
			(justify right)
		)
		(property "Intersheetrefs" "${INTERSHEET_REFS}"
			(at 29.845 0.635 0)
			(effects
				(font
					(size 1.27 1.27)
				)
				(hide yes)
			)
		)
	)
	(global_label "NCSI_TXD1"
		(shape input)
		(at 231.14 133.35 0)
		(fields_autoplaced yes)
		(effects
			(font
				(size 1.27 1.27)
			)
			(justify left)
		)
		(property "Intersheetrefs" "${INTERSHEET_REFS}"
			(at -0.635 0.635 0)
			(effects
				(font
					(size 1.27 1.27)
				)
				(justify right)
				(hide yes)
			)
		)
	)
	(global_label "I2C[1]_SDA"
		(shape input)
		(at 198.12 87.63 180)
		(fields_autoplaced yes)
		(effects
			(font
				(size 1.27 1.27)
			)
			(justify right)
		)
		(property "Intersheetrefs" "${INTERSHEET_REFS}"
			(at 29.845 0.635 0)
			(effects
				(font
					(size 1.27 1.27)
				)
				(hide yes)
			)
		)
	)
	(global_label "PCIE_HPM_TX[1]_N"
		(shape input)
		(at 231.14 247.65 0)
		(fields_autoplaced yes)
		(effects
			(font
				(size 1.27 1.27)
			)
			(justify left)
		)
		(property "Intersheetrefs" "${INTERSHEET_REFS}"
			(at -0.635 0.635 0)
			(effects
				(font
					(size 1.27 1.27)
				)
				(justify right)
				(hide yes)
			)
		)
	)
	(global_label "I3C[3]_SCL"
		(shape input)
		(at 187.96 64.77 180)
		(fields_autoplaced yes)
		(effects
			(font
				(size 1.27 1.27)
			)
			(justify right)
		)
		(property "Intersheetrefs" "${INTERSHEET_REFS}"
			(at 19.685 0.635 0)
			(effects
				(font
					(size 1.27 1.27)
				)
				(hide yes)
			)
		)
	)
	(global_label "JTAG_TMS"
		(shape input)
		(at 198.12 171.45 180)
		(fields_autoplaced yes)
		(effects
			(font
				(size 1.27 1.27)
			)
			(justify right)
		)
		(property "Intersheetrefs" "${INTERSHEET_REFS}"
			(at 29.845 0.635 0)
			(effects
				(font
					(size 1.27 1.27)
				)
				(hide yes)
			)
		)
	)
	(global_label "I3C[0]_SCL"
		(shape input)
		(at 187.96 49.53 180)
		(fields_autoplaced yes)
		(effects
			(font
				(size 1.27 1.27)
			)
			(justify right)
		)
		(property "Intersheetrefs" "${INTERSHEET_REFS}"
			(at 19.685 0.635 0)
			(effects
				(font
					(size 1.27 1.27)
				)
				(hide yes)
			)
		)
	)
	(global_label "SPARE0_R"
		(shape input)
		(at 165.1 227.33 180)
		(fields_autoplaced yes)
		(effects
			(font
				(size 1.27 1.27)
			)
			(justify right)
		)
		(property "Intersheetrefs" "${INTERSHEET_REFS}"
			(at 128.905 -22.225 0)
			(effects
				(font
					(size 1.27 1.27)
				)
				(justify right)
				(hide yes)
			)
		)
	)
	(global_label "JTAG_TDO"
		(shape input)
		(at 198.12 176.53 180)
		(fields_autoplaced yes)
		(effects
			(font
				(size 1.27 1.27)
			)
			(justify right)
		)
		(property "Intersheetrefs" "${INTERSHEET_REFS}"
			(at 29.845 0.635 0)
			(effects
				(font
					(size 1.27 1.27)
				)
				(hide yes)
			)
		)
	)
	(global_label "I2C[7]_SDA"
		(shape input)
		(at 198.12 143.51 180)
		(fields_autoplaced yes)
		(effects
			(font
				(size 1.27 1.27)
			)
			(justify right)
		)
		(property "Intersheetrefs" "${INTERSHEET_REFS}"
			(at 29.845 0.635 0)
			(effects
				(font
					(size 1.27 1.27)
				)
				(hide yes)
			)
		)
	)
	(global_label "UART0_SCM_RX"
		(shape input)
		(at 241.3 59.69 0)
		(fields_autoplaced yes)
		(effects
			(font
				(size 1.27 1.27)
			)
			(justify left)
		)
		(property "Intersheetrefs" "${INTERSHEET_REFS}"
			(at 9.525 0.635 0)
			(effects
				(font
					(size 1.27 1.27)
				)
				(justify right)
				(hide yes)
			)
		)
	)
	(global_label "I2C[5]_SDA"
		(shape input)
		(at 198.12 107.95 180)
		(fields_autoplaced yes)
		(effects
			(font
				(size 1.27 1.27)
			)
			(justify right)
		)
		(property "Intersheetrefs" "${INTERSHEET_REFS}"
			(at 29.845 0.635 0)
			(effects
				(font
					(size 1.27 1.27)
				)
				(hide yes)
			)
		)
	)
	(global_label "I2C[9]_SCL"
		(shape input)
		(at 198.12 156.21 180)
		(fields_autoplaced yes)
		(effects
			(font
				(size 1.27 1.27)
			)
			(justify right)
		)
		(property "Intersheetrefs" "${INTERSHEET_REFS}"
			(at 29.845 0.635 0)
			(effects
				(font
					(size 1.27 1.27)
				)
				(hide yes)
			)
		)
	)
	(global_label "USB2_D_N"
		(shape input)
		(at 231.14 217.17 0)
		(fields_autoplaced yes)
		(effects
			(font
				(size 1.27 1.27)
			)
			(justify left)
		)
		(property "Intersheetrefs" "${INTERSHEET_REFS}"
			(at -0.635 0.635 0)
			(effects
				(font
					(size 1.27 1.27)
				)
				(justify right)
				(hide yes)
			)
		)
	)
	(global_label "SYS_PWRBTN_N_R"
		(shape input)
		(at 165.1 207.01 180)
		(fields_autoplaced yes)
		(effects
			(font
				(size 1.27 1.27)
			)
			(justify right)
		)
		(property "Intersheetrefs" "${INTERSHEET_REFS}"
			(at 128.905 -16.51 0)
			(effects
				(font
					(size 1.27 1.27)
				)
				(justify right)
				(hide yes)
			)
		)
	)
	(global_label "PCIE_HPM_TX[2]_N"
		(shape input)
		(at 231.14 255.27 0)
		(fields_autoplaced yes)
		(effects
			(font
				(size 1.27 1.27)
			)
			(justify left)
		)
		(property "Intersheetrefs" "${INTERSHEET_REFS}"
			(at -0.635 0.635 0)
			(effects
				(font
					(size 1.27 1.27)
				)
				(justify right)
				(hide yes)
			)
		)
	)
	(global_label "SPI0_CLK_R"
		(shape input)
		(at 300.99 64.77 0)
		(fields_autoplaced yes)
		(effects
			(font
				(size 1.27 1.27)
			)
			(justify left)
		)
		(property "Intersheetrefs" "${INTERSHEET_REFS}"
			(at 337.185 -143.51 0)
			(effects
				(font
					(size 1.27 1.27)
				)
				(justify left)
				(hide yes)
			)
		)
	)
	(global_label "QSPI0_CLK"
		(shape input)
		(at 231.14 105.41 0)
		(fields_autoplaced yes)
		(effects
			(font
				(size 1.27 1.27)
			)
			(justify left)
		)
		(property "Intersheetrefs" "${INTERSHEET_REFS}"
			(at -0.635 0.635 0)
			(effects
				(font
					(size 1.27 1.27)
				)
				(justify right)
				(hide yes)
			)
		)
	)
	(global_label "ESPI_CS1_N_1V8"
		(shape input)
		(at 264.16 100.33 0)
		(fields_autoplaced yes)
		(effects
			(font
				(size 1.27 1.27)
			)
			(justify left)
		)
		(property "Intersheetrefs" "${INTERSHEET_REFS}"
			(at 32.385 0.635 0)
			(effects
				(font
					(size 1.27 1.27)
				)
				(justify right)
				(hide yes)
			)
		)
	)
	(global_label "PCIE_HPM_RX[1]_N"
		(shape input)
		(at 198.12 247.65 180)
		(fields_autoplaced yes)
		(effects
			(font
				(size 1.27 1.27)
			)
			(justify right)
		)
		(property "Intersheetrefs" "${INTERSHEET_REFS}"
			(at 29.845 0.635 0)
			(effects
				(font
					(size 1.27 1.27)
				)
				(hide yes)
			)
		)
	)
	(global_label "PCIE_HPM_TX[1]_P"
		(shape input)
		(at 231.14 245.11 0)
		(fields_autoplaced yes)
		(effects
			(font
				(size 1.27 1.27)
			)
			(justify left)
		)
		(property "Intersheetrefs" "${INTERSHEET_REFS}"
			(at -0.635 0.635 0)
			(effects
				(font
					(size 1.27 1.27)
				)
				(justify right)
				(hide yes)
			)
		)
	)
	(global_label "DBP_PRDY_N_R"
		(shape input)
		(at 165.1 214.63 180)
		(fields_autoplaced yes)
		(effects
			(font
				(size 1.27 1.27)
			)
			(justify right)
		)
		(property "Intersheetrefs" "${INTERSHEET_REFS}"
			(at 128.905 -19.685 0)
			(effects
				(font
					(size 1.27 1.27)
				)
				(justify right)
				(hide yes)
			)
		)
	)
	(global_label "ESPI_CS0_N_1V8"
		(shape input)
		(at 231.14 82.55 0)
		(fields_autoplaced yes)
		(effects
			(font
				(size 1.27 1.27)
			)
			(justify left)
		)
		(property "Intersheetrefs" "${INTERSHEET_REFS}"
			(at -0.635 0.635 0)
			(effects
				(font
					(size 1.27 1.27)
				)
				(justify right)
				(hide yes)
			)
		)
	)
	(global_label "PRSNT0_N_R"
		(shape input)
		(at 264.16 44.45 0)
		(fields_autoplaced yes)
		(effects
			(font
				(size 1.27 1.27)
			)
			(justify left)
		)
		(property "Intersheetrefs" "${INTERSHEET_REFS}"
			(at 351.155 -153.67 0)
			(effects
				(font
					(size 1.27 1.27)
				)
				(justify left)
				(hide yes)
			)
		)
	)
	(global_label "RoT_CPU_RST_N_R"
		(shape input)
		(at 165.1 222.25 180)
		(fields_autoplaced yes)
		(effects
			(font
				(size 1.27 1.27)
			)
			(justify right)
		)
		(property "Intersheetrefs" "${INTERSHEET_REFS}"
			(at 128.905 -22.225 0)
			(effects
				(font
					(size 1.27 1.27)
				)
				(justify right)
				(hide yes)
			)
		)
	)
	(global_label "I3C[3]_SDA"
		(shape input)
		(at 187.96 67.31 180)
		(fields_autoplaced yes)
		(effects
			(font
				(size 1.27 1.27)
			)
			(justify right)
		)
		(property "Intersheetrefs" "${INTERSHEET_REFS}"
			(at 19.685 0.635 0)
			(effects
				(font
					(size 1.27 1.27)
				)
				(hide yes)
			)
		)
	)
	(global_label "IRQ_N_R"
		(shape input)
		(at 165.1 229.87 180)
		(fields_autoplaced yes)
		(effects
			(font
				(size 1.27 1.27)
			)
			(justify right)
		)
		(property "Intersheetrefs" "${INTERSHEET_REFS}"
			(at 128.905 -24.765 0)
			(effects
				(font
					(size 1.27 1.27)
				)
				(justify right)
				(hide yes)
			)
		)
	)
	(global_label "SPI0_MOSI"
		(shape input)
		(at 300.99 58.42 0)
		(fields_autoplaced yes)
		(effects
			(font
				(size 1.27 1.27)
			)
			(justify left)
		)
		(property "Intersheetrefs" "${INTERSHEET_REFS}"
			(at 69.215 -10.795 0)
			(effects
				(font
					(size 1.27 1.27)
				)
				(justify right)
				(hide yes)
			)
		)
	)
	(global_label "HPM_STBY_RDY_R"
		(shape input)
		(at 165.1 199.39 180)
		(fields_autoplaced yes)
		(effects
			(font
				(size 1.27 1.27)
			)
			(justify right)
		)
		(property "Intersheetrefs" "${INTERSHEET_REFS}"
			(at 129.54 -80.645 0)
			(effects
				(font
					(size 1.27 1.27)
				)
				(justify right)
				(hide yes)
			)
		)
	)
	(global_label "PCIE_BMC_TX_P"
		(shape input)
		(at 198.12 120.65 180)
		(fields_autoplaced yes)
		(effects
			(font
				(size 1.27 1.27)
			)
			(justify right)
		)
		(property "Intersheetrefs" "${INTERSHEET_REFS}"
			(at 29.845 0.635 0)
			(effects
				(font
					(size 1.27 1.27)
				)
				(hide yes)
			)
		)
	)
	(global_label "SPI0_MISO"
		(shape input)
		(at 300.99 60.96 0)
		(fields_autoplaced yes)
		(effects
			(font
				(size 1.27 1.27)
			)
			(justify left)
		)
		(property "Intersheetrefs" "${INTERSHEET_REFS}"
			(at 69.215 -10.795 0)
			(effects
				(font
					(size 1.27 1.27)
				)
				(justify right)
				(hide yes)
			)
		)
	)
	(global_label "PCIE_HPM_CLK_N"
		(shape input)
		(at 269.24 232.41 0)
		(fields_autoplaced yes)
		(effects
			(font
				(size 1.27 1.27)
			)
			(justify left)
		)
		(property "Intersheetrefs" "${INTERSHEET_REFS}"
			(at 37.465 0.635 0)
			(effects
				(font
					(size 1.27 1.27)
				)
				(justify right)
				(hide yes)
			)
		)
	)
	(global_label "NCSI_CRS_DV"
		(shape input)
		(at 231.14 125.73 0)
		(fields_autoplaced yes)
		(effects
			(font
				(size 1.27 1.27)
			)
			(justify left)
		)
		(property "Intersheetrefs" "${INTERSHEET_REFS}"
			(at -0.635 0.635 0)
			(effects
				(font
					(size 1.27 1.27)
				)
				(justify right)
				(hide yes)
			)
		)
	)
	(global_label "PCIE_HPM_TX[0]_N"
		(shape input)
		(at 231.14 240.03 0)
		(fields_autoplaced yes)
		(effects
			(font
				(size 1.27 1.27)
			)
			(justify left)
		)
		(property "Intersheetrefs" "${INTERSHEET_REFS}"
			(at -0.635 0.635 0)
			(effects
				(font
					(size 1.27 1.27)
				)
				(justify right)
				(hide yes)
			)
		)
	)
	(global_label "NCSI_TXEN"
		(shape input)
		(at 231.14 128.27 0)
		(fields_autoplaced yes)
		(effects
			(font
				(size 1.27 1.27)
			)
			(justify left)
		)
		(property "Intersheetrefs" "${INTERSHEET_REFS}"
			(at -0.635 0.635 0)
			(effects
				(font
					(size 1.27 1.27)
				)
				(justify right)
				(hide yes)
			)
		)
	)
	(global_label "SPI0_MOSI_R"
		(shape input)
		(at 300.99 69.85 0)
		(fields_autoplaced yes)
		(effects
			(font
				(size 1.27 1.27)
			)
			(justify left)
		)
		(property "Intersheetrefs" "${INTERSHEET_REFS}"
			(at 337.185 -123.19 0)
			(effects
				(font
					(size 1.27 1.27)
				)
				(justify left)
				(hide yes)
			)
		)
	)
	(global_label "ESPI_ALERT_N_1V8"
		(shape input)
		(at 231.14 85.09 0)
		(fields_autoplaced yes)
		(effects
			(font
				(size 1.27 1.27)
			)
			(justify left)
		)
		(property "Intersheetrefs" "${INTERSHEET_REFS}"
			(at -0.635 0.635 0)
			(effects
				(font
					(size 1.27 1.27)
				)
				(justify right)
				(hide yes)
			)
		)
	)
	(global_label "QSPI1_D1"
		(shape input)
		(at 231.14 204.47 0)
		(fields_autoplaced yes)
		(effects
			(font
				(size 1.27 1.27)
			)
			(justify left)
		)
		(property "Intersheetrefs" "${INTERSHEET_REFS}"
			(at -0.635 0.635 0)
			(effects
				(font
					(size 1.27 1.27)
				)
				(justify right)
				(hide yes)
			)
		)
	)
	(global_label "I3C[2]_SDA"
		(shape input)
		(at 187.96 62.23 180)
		(fields_autoplaced yes)
		(effects
			(font
				(size 1.27 1.27)
			)
			(justify right)
		)
		(property "Intersheetrefs" "${INTERSHEET_REFS}"
			(at 19.685 0.635 0)
			(effects
				(font
					(size 1.27 1.27)
				)
				(hide yes)
			)
		)
	)
	(global_label "PECI_BMC"
		(shape input)
		(at 231.14 146.05 0)
		(fields_autoplaced yes)
		(effects
			(font
				(size 1.27 1.27)
			)
			(justify left)
		)
		(property "Intersheetrefs" "${INTERSHEET_REFS}"
			(at -0.635 0.635 0)
			(effects
				(font
					(size 1.27 1.27)
				)
				(hide yes)
			)
		)
	)
	(global_label "I2C[7]_SCL"
		(shape input)
		(at 198.12 140.97 180)
		(fields_autoplaced yes)
		(effects
			(font
				(size 1.27 1.27)
			)
			(justify right)
		)
		(property "Intersheetrefs" "${INTERSHEET_REFS}"
			(at 29.845 0.635 0)
			(effects
				(font
					(size 1.27 1.27)
				)
				(hide yes)
			)
		)
	)
	(global_label "NCSI_TXD0"
		(shape input)
		(at 231.14 130.81 0)
		(fields_autoplaced yes)
		(effects
			(font
				(size 1.27 1.27)
			)
			(justify left)
		)
		(property "Intersheetrefs" "${INTERSHEET_REFS}"
			(at -0.635 0.635 0)
			(effects
				(font
					(size 1.27 1.27)
				)
				(justify right)
				(hide yes)
			)
		)
	)
	(global_label "I2C[5]_SCL"
		(shape input)
		(at 198.12 105.41 180)
		(fields_autoplaced yes)
		(effects
			(font
				(size 1.27 1.27)
			)
			(justify right)
		)
		(property "Intersheetrefs" "${INTERSHEET_REFS}"
			(at 29.845 0.635 0)
			(effects
				(font
					(size 1.27 1.27)
				)
				(hide yes)
			)
		)
	)
	(global_label "QSPI1_CS0_N"
		(shape input)
		(at 231.14 199.39 0)
		(fields_autoplaced yes)
		(effects
			(font
				(size 1.27 1.27)
			)
			(justify left)
		)
		(property "Intersheetrefs" "${INTERSHEET_REFS}"
			(at -0.635 0.635 0)
			(effects
				(font
					(size 1.27 1.27)
				)
				(justify right)
				(hide yes)
			)
		)
	)
	(global_label "VIRTUAL_RESEAT_R"
		(shape input)
		(at 166.37 72.39 180)
		(fields_autoplaced yes)
		(effects
			(font
				(size 1.27 1.27)
			)
			(justify right)
		)
		(property "Intersheetrefs" "${INTERSHEET_REFS}"
			(at 79.375 -120.65 0)
			(effects
				(font
					(size 1.27 1.27)
				)
				(justify right)
				(hide yes)
			)
		)
	)
	(global_label "NCSI_RXER"
		(shape input)
		(at 231.14 135.89 0)
		(fields_autoplaced yes)
		(effects
			(font
				(size 1.27 1.27)
			)
			(justify left)
		)
		(property "Intersheetrefs" "${INTERSHEET_REFS}"
			(at -0.635 0.635 0)
			(effects
				(font
					(size 1.27 1.27)
				)
				(justify right)
				(hide yes)
			)
		)
	)
	(global_label "ESPI_IO1_1V8"
		(shape input)
		(at 231.14 92.71 0)
		(fields_autoplaced yes)
		(effects
			(font
				(size 1.27 1.27)
			)
			(justify left)
		)
		(property "Intersheetrefs" "${INTERSHEET_REFS}"
			(at -0.635 0.635 0)
			(effects
				(font
					(size 1.27 1.27)
				)
				(justify right)
				(hide yes)
			)
		)
	)
	(global_label "PCIE_HPM_TX[2]_P"
		(shape input)
		(at 231.14 252.73 0)
		(fields_autoplaced yes)
		(effects
			(font
				(size 1.27 1.27)
			)
			(justify left)
		)
		(property "Intersheetrefs" "${INTERSHEET_REFS}"
			(at -0.635 0.635 0)
			(effects
				(font
					(size 1.27 1.27)
				)
				(justify right)
				(hide yes)
			)
		)
	)
	(global_label "QSPI0_CS1_N"
		(shape input)
		(at 231.14 189.23 0)
		(fields_autoplaced yes)
		(effects
			(font
				(size 1.27 1.27)
			)
			(justify left)
		)
		(property "Intersheetrefs" "${INTERSHEET_REFS}"
			(at -0.635 0.635 0)
			(effects
				(font
					(size 1.27 1.27)
				)
				(justify right)
				(hide yes)
			)
		)
	)
	(global_label "I2C[10]_SCL"
		(shape input)
		(at 198.12 161.29 180)
		(fields_autoplaced yes)
		(effects
			(font
				(size 1.27 1.27)
			)
			(justify right)
		)
		(property "Intersheetrefs" "${INTERSHEET_REFS}"
			(at 29.845 0.635 0)
			(effects
				(font
					(size 1.27 1.27)
				)
				(hide yes)
			)
		)
	)
	(global_label "SGPIO0_DO"
		(shape input)
		(at 231.14 156.21 0)
		(fields_autoplaced yes)
		(effects
			(font
				(size 1.27 1.27)
			)
			(justify left)
		)
		(property "Intersheetrefs" "${INTERSHEET_REFS}"
			(at -0.635 0.635 0)
			(effects
				(font
					(size 1.27 1.27)
				)
				(justify right)
				(hide yes)
			)
		)
	)
	(global_label "I2C[2]_SCL"
		(shape input)
		(at 198.12 90.17 180)
		(fields_autoplaced yes)
		(effects
			(font
				(size 1.27 1.27)
			)
			(justify right)
		)
		(property "Intersheetrefs" "${INTERSHEET_REFS}"
			(at 29.845 0.635 0)
			(effects
				(font
					(size 1.27 1.27)
				)
				(hide yes)
			)
		)
	)
	(global_label "I3C[0]_SDA"
		(shape input)
		(at 187.96 52.07 180)
		(fields_autoplaced yes)
		(effects
			(font
				(size 1.27 1.27)
			)
			(justify right)
		)
		(property "Intersheetrefs" "${INTERSHEET_REFS}"
			(at 19.685 0.635 0)
			(effects
				(font
					(size 1.27 1.27)
				)
				(hide yes)
			)
		)
	)
	(global_label "UART0_SCM_TX"
		(shape input)
		(at 241.3 57.15 0)
		(fields_autoplaced yes)
		(effects
			(font
				(size 1.27 1.27)
			)
			(justify left)
		)
		(property "Intersheetrefs" "${INTERSHEET_REFS}"
			(at 9.525 0.635 0)
			(effects
				(font
					(size 1.27 1.27)
				)
				(justify right)
				(hide yes)
			)
		)
	)
	(global_label "JTAG_TDI"
		(shape input)
		(at 198.12 173.99 180)
		(fields_autoplaced yes)
		(effects
			(font
				(size 1.27 1.27)
			)
			(justify right)
		)
		(property "Intersheetrefs" "${INTERSHEET_REFS}"
			(at 29.845 0.635 0)
			(effects
				(font
					(size 1.27 1.27)
				)
				(hide yes)
			)
		)
	)
	(global_label "SGPIO0_LD"
		(shape input)
		(at 231.14 163.83 0)
		(fields_autoplaced yes)
		(effects
			(font
				(size 1.27 1.27)
			)
			(justify left)
		)
		(property "Intersheetrefs" "${INTERSHEET_REFS}"
			(at -0.635 0.635 0)
			(effects
				(font
					(size 1.27 1.27)
				)
				(justify right)
				(hide yes)
			)
		)
	)
	(global_label "SGPIO1_LD"
		(shape input)
		(at 231.14 176.53 0)
		(fields_autoplaced yes)
		(effects
			(font
				(size 1.27 1.27)
			)
			(justify left)
		)
		(property "Intersheetrefs" "${INTERSHEET_REFS}"
			(at -0.635 0.635 0)
			(effects
				(font
					(size 1.27 1.27)
				)
				(justify right)
				(hide yes)
			)
		)
	)
	(global_label "I2C[8]_SCL"
		(shape input)
		(at 198.12 146.05 180)
		(fields_autoplaced yes)
		(effects
			(font
				(size 1.27 1.27)
			)
			(justify right)
		)
		(property "Intersheetrefs" "${INTERSHEET_REFS}"
			(at 29.845 0.635 0)
			(effects
				(font
					(size 1.27 1.27)
				)
				(hide yes)
			)
		)
	)
	(global_label "SPI0_CS_N_R"
		(shape input)
		(at 300.99 67.31 0)
		(fields_autoplaced yes)
		(effects
			(font
				(size 1.27 1.27)
			)
			(justify left)
		)
		(property "Intersheetrefs" "${INTERSHEET_REFS}"
			(at 337.185 -135.89 0)
			(effects
				(font
					(size 1.27 1.27)
				)
				(justify left)
				(hide yes)
			)
		)
	)
	(global_label "I3C[1]_SCL"
		(shape input)
		(at 187.96 54.61 180)
		(fields_autoplaced yes)
		(effects
			(font
				(size 1.27 1.27)
			)
			(justify right)
		)
		(property "Intersheetrefs" "${INTERSHEET_REFS}"
			(at 19.685 0.635 0)
			(effects
				(font
					(size 1.27 1.27)
				)
				(hide yes)
			)
		)
	)
	(global_label "QSPI0_CS0_N"
		(shape input)
		(at 231.14 107.95 0)
		(fields_autoplaced yes)
		(effects
			(font
				(size 1.27 1.27)
			)
			(justify left)
		)
		(property "Intersheetrefs" "${INTERSHEET_REFS}"
			(at -0.635 0.635 0)
			(effects
				(font
					(size 1.27 1.27)
				)
				(justify right)
				(hide yes)
			)
		)
	)
	(global_label "I2C[12]_SDA"
		(shape input)
		(at 198.12 186.69 180)
		(fields_autoplaced yes)
		(effects
			(font
				(size 1.27 1.27)
			)
			(justify right)
		)
		(property "Intersheetrefs" "${INTERSHEET_REFS}"
			(at 29.845 0.635 0)
			(effects
				(font
					(size 1.27 1.27)
				)
				(hide yes)
			)
		)
	)
	(global_label "ESPI_IO0_1V8"
		(shape input)
		(at 231.14 90.17 0)
		(fields_autoplaced yes)
		(effects
			(font
				(size 1.27 1.27)
			)
			(justify left)
		)
		(property "Intersheetrefs" "${INTERSHEET_REFS}"
			(at -0.635 0.635 0)
			(effects
				(font
					(size 1.27 1.27)
				)
				(justify right)
				(hide yes)
			)
		)
	)
	(global_label "I2C[1]_SCL"
		(shape input)
		(at 198.12 85.09 180)
		(fields_autoplaced yes)
		(effects
			(font
				(size 1.27 1.27)
			)
			(justify right)
		)
		(property "Intersheetrefs" "${INTERSHEET_REFS}"
			(at 29.845 0.635 0)
			(effects
				(font
					(size 1.27 1.27)
				)
				(hide yes)
			)
		)
	)
	(global_label "I2C[6]_SDA"
		(shape input)
		(at 198.12 138.43 180)
		(fields_autoplaced yes)
		(effects
			(font
				(size 1.27 1.27)
			)
			(justify right)
		)
		(property "Intersheetrefs" "${INTERSHEET_REFS}"
			(at 29.845 0.635 0)
			(effects
				(font
					(size 1.27 1.27)
				)
				(hide yes)
			)
		)
	)
	(global_label "SPI0_CS_N"
		(shape input)
		(at 300.99 55.88 0)
		(fields_autoplaced yes)
		(effects
			(font
				(size 1.27 1.27)
			)
			(justify left)
		)
		(property "Intersheetrefs" "${INTERSHEET_REFS}"
			(at 69.215 -10.795 0)
			(effects
				(font
					(size 1.27 1.27)
				)
				(justify right)
				(hide yes)
			)
		)
	)
	(global_label "PCIE_BMC_TX_N"
		(shape input)
		(at 198.12 123.19 180)
		(fields_autoplaced yes)
		(effects
			(font
				(size 1.27 1.27)
			)
			(justify right)
		)
		(property "Intersheetrefs" "${INTERSHEET_REFS}"
			(at 29.845 0.635 0)
			(effects
				(font
					(size 1.27 1.27)
				)
				(hide yes)
			)
		)
	)
	(global_label "I2C[12]_SCL"
		(shape input)
		(at 198.12 184.15 180)
		(fields_autoplaced yes)
		(effects
			(font
				(size 1.27 1.27)
			)
			(justify right)
		)
		(property "Intersheetrefs" "${INTERSHEET_REFS}"
			(at 29.845 0.635 0)
			(effects
				(font
					(size 1.27 1.27)
				)
				(hide yes)
			)
		)
	)
	(global_label "I2C[10]_SDA"
		(shape input)
		(at 198.12 163.83 180)
		(fields_autoplaced yes)
		(effects
			(font
				(size 1.27 1.27)
			)
			(justify right)
		)
		(property "Intersheetrefs" "${INTERSHEET_REFS}"
			(at 29.845 0.635 0)
			(effects
				(font
					(size 1.27 1.27)
				)
				(hide yes)
			)
		)
	)
	(global_label "PCIE_HPM_RX[1]_P"
		(shape input)
		(at 198.12 245.11 180)
		(fields_autoplaced yes)
		(effects
			(font
				(size 1.27 1.27)
			)
			(justify right)
		)
		(property "Intersheetrefs" "${INTERSHEET_REFS}"
			(at 29.845 0.635 0)
			(effects
				(font
					(size 1.27 1.27)
				)
				(hide yes)
			)
		)
	)
	(global_label "SYS_PWROK_R"
		(shape input)
		(at 165.1 209.55 180)
		(fields_autoplaced yes)
		(effects
			(font
				(size 1.27 1.27)
			)
			(justify right)
		)
		(property "Intersheetrefs" "${INTERSHEET_REFS}"
			(at 128.905 -19.685 0)
			(effects
				(font
					(size 1.27 1.27)
				)
				(justify right)
				(hide yes)
			)
		)
	)
	(global_label "SPI0_MISO_R"
		(shape input)
		(at 300.99 72.39 0)
		(fields_autoplaced yes)
		(effects
			(font
				(size 1.27 1.27)
			)
			(justify left)
		)
		(property "Intersheetrefs" "${INTERSHEET_REFS}"
			(at 337.185 -125.73 0)
			(effects
				(font
					(size 1.27 1.27)
				)
				(justify left)
				(hide yes)
			)
		)
	)
	(global_label "PCIE_HPM_RX[2]_N"
		(shape input)
		(at 198.12 255.27 180)
		(fields_autoplaced yes)
		(effects
			(font
				(size 1.27 1.27)
			)
			(justify right)
		)
		(property "Intersheetrefs" "${INTERSHEET_REFS}"
			(at 29.845 0.635 0)
			(effects
				(font
					(size 1.27 1.27)
				)
				(hide yes)
			)
		)
	)
	(global_label "PCIE_BMC_RX_N"
		(shape input)
		(at 198.12 130.81 180)
		(fields_autoplaced yes)
		(effects
			(font
				(size 1.27 1.27)
			)
			(justify right)
		)
		(property "Intersheetrefs" "${INTERSHEET_REFS}"
			(at 29.845 0.635 0)
			(effects
				(font
					(size 1.27 1.27)
				)
				(hide yes)
			)
		)
	)
	(global_label "USB1_D_N"
		(shape input)
		(at 231.14 224.79 0)
		(fields_autoplaced yes)
		(effects
			(font
				(size 1.27 1.27)
			)
			(justify left)
		)
		(property "Intersheetrefs" "${INTERSHEET_REFS}"
			(at -0.635 0.635 0)
			(effects
				(font
					(size 1.27 1.27)
				)
				(justify right)
				(hide yes)
			)
		)
	)
	(global_label "SPARE1_R"
		(shape input)
		(at 165.1 219.71 180)
		(fields_autoplaced yes)
		(effects
			(font
				(size 1.27 1.27)
			)
			(justify right)
		)
		(property "Intersheetrefs" "${INTERSHEET_REFS}"
			(at 128.905 -40.005 0)
			(effects
				(font
					(size 1.27 1.27)
				)
				(justify right)
				(hide yes)
			)
		)
	)
	(global_label "UART1_SCM_TX"
		(shape input)
		(at 241.3 49.53 0)
		(fields_autoplaced yes)
		(effects
			(font
				(size 1.27 1.27)
			)
			(justify left)
		)
		(property "Intersheetrefs" "${INTERSHEET_REFS}"
			(at 9.525 0.635 0)
			(effects
				(font
					(size 1.27 1.27)
				)
				(justify right)
				(hide yes)
			)
		)
	)
	(global_label "DBP_PREQ_N_R"
		(shape input)
		(at 165.1 212.09 180)
		(fields_autoplaced yes)
		(effects
			(font
				(size 1.27 1.27)
			)
			(justify right)
		)
		(property "Intersheetrefs" "${INTERSHEET_REFS}"
			(at 128.905 -57.785 0)
			(effects
				(font
					(size 1.27 1.27)
				)
				(justify right)
				(hide yes)
			)
		)
	)
	(global_label "PVCCIO_PECI"
		(shape input)
		(at 144.78 59.69 180)
		(fields_autoplaced yes)
		(effects
			(font
				(size 1.27 1.27)
			)
			(justify right)
		)
		(property "Intersheetrefs" "${INTERSHEET_REFS}"
			(at 403.225 -88.9 0)
			(effects
				(font
					(size 1.27 1.27)
				)
				(justify left)
				(hide yes)
			)
		)
	)
	(global_label "PCIE_HPM_RX[2]_P"
		(shape input)
		(at 198.12 252.73 180)
		(fields_autoplaced yes)
		(effects
			(font
				(size 1.27 1.27)
			)
			(justify right)
		)
		(property "Intersheetrefs" "${INTERSHEET_REFS}"
			(at 29.845 0.635 0)
			(effects
				(font
					(size 1.27 1.27)
				)
				(hide yes)
			)
		)
	)
	(global_label "QSPI1_D2"
		(shape input)
		(at 231.14 207.01 0)
		(fields_autoplaced yes)
		(effects
			(font
				(size 1.27 1.27)
			)
			(justify left)
		)
		(property "Intersheetrefs" "${INTERSHEET_REFS}"
			(at -0.635 0.635 0)
			(effects
				(font
					(size 1.27 1.27)
				)
				(justify right)
				(hide yes)
			)
		)
	)
	(global_label "UART1_SCM_RX"
		(shape input)
		(at 241.3 52.07 0)
		(fields_autoplaced yes)
		(effects
			(font
				(size 1.27 1.27)
			)
			(justify left)
		)
		(property "Intersheetrefs" "${INTERSHEET_REFS}"
			(at 9.525 0.635 0)
			(effects
				(font
					(size 1.27 1.27)
				)
				(justify right)
				(hide yes)
			)
		)
	)
	(global_label "I2C[8]_SDA"
		(shape input)
		(at 198.12 148.59 180)
		(fields_autoplaced yes)
		(effects
			(font
				(size 1.27 1.27)
			)
			(justify right)
		)
		(property "Intersheetrefs" "${INTERSHEET_REFS}"
			(at 29.845 0.635 0)
			(effects
				(font
					(size 1.27 1.27)
				)
				(hide yes)
			)
		)
	)
	(global_label "QSPI0_D1"
		(shape input)
		(at 231.14 113.03 0)
		(fields_autoplaced yes)
		(effects
			(font
				(size 1.27 1.27)
			)
			(justify left)
		)
		(property "Intersheetrefs" "${INTERSHEET_REFS}"
			(at -0.635 0.635 0)
			(effects
				(font
					(size 1.27 1.27)
				)
				(justify right)
				(hide yes)
			)
		)
	)
	(global_label "I2C[11]_SCL"
		(shape input)
		(at 198.12 179.07 180)
		(fields_autoplaced yes)
		(effects
			(font
				(size 1.27 1.27)
			)
			(justify right)
		)
		(property "Intersheetrefs" "${INTERSHEET_REFS}"
			(at 29.845 0.635 0)
			(effects
				(font
					(size 1.27 1.27)
				)
				(hide yes)
			)
		)
	)
	(global_label "P12V_AUX"
		(shape input)
		(at 242.57 39.37 0)
		(fields_autoplaced yes)
		(effects
			(font
				(size 1.27 1.27)
			)
			(justify left)
		)
		(property "Intersheetrefs" "${INTERSHEET_REFS}"
			(at 410.845 0.635 0)
			(effects
				(font
					(size 1.27 1.27)
				)
				(hide yes)
			)
		)
	)
	(global_label "QSPI1_D0"
		(shape input)
		(at 231.14 201.93 0)
		(fields_autoplaced yes)
		(effects
			(font
				(size 1.27 1.27)
			)
			(justify left)
		)
		(property "Intersheetrefs" "${INTERSHEET_REFS}"
			(at -0.635 0.635 0)
			(effects
				(font
					(size 1.27 1.27)
				)
				(justify right)
				(hide yes)
			)
		)
	)
	(global_label "QSPI0_D0"
		(shape input)
		(at 231.14 110.49 0)
		(fields_autoplaced yes)
		(effects
			(font
				(size 1.27 1.27)
			)
			(justify left)
		)
		(property "Intersheetrefs" "${INTERSHEET_REFS}"
			(at -0.635 0.635 0)
			(effects
				(font
					(size 1.27 1.27)
				)
				(justify right)
				(hide yes)
			)
		)
	)
	(global_label "SGPIO1_DO"
		(shape input)
		(at 231.14 168.91 0)
		(fields_autoplaced yes)
		(effects
			(font
				(size 1.27 1.27)
			)
			(justify left)
		)
		(property "Intersheetrefs" "${INTERSHEET_REFS}"
			(at -0.635 0.635 0)
			(effects
				(font
					(size 1.27 1.27)
				)
				(justify right)
				(hide yes)
			)
		)
	)
	(global_label "ESPI_RESET_N_1V8"
		(shape input)
		(at 231.14 87.63 0)
		(fields_autoplaced yes)
		(effects
			(font
				(size 1.27 1.27)
			)
			(justify left)
		)
		(property "Intersheetrefs" "${INTERSHEET_REFS}"
			(at -0.635 0.635 0)
			(effects
				(font
					(size 1.27 1.27)
				)
				(justify right)
				(hide yes)
			)
		)
	)
	(global_label "SGPIO1_DI"
		(shape input)
		(at 231.14 173.99 0)
		(fields_autoplaced yes)
		(effects
			(font
				(size 1.27 1.27)
			)
			(justify left)
		)
		(property "Intersheetrefs" "${INTERSHEET_REFS}"
			(at -0.635 0.635 0)
			(effects
				(font
					(size 1.27 1.27)
				)
				(justify right)
				(hide yes)
			)
		)
	)
	(global_label "ESPI_IO2_1V8"
		(shape input)
		(at 231.14 95.25 0)
		(fields_autoplaced yes)
		(effects
			(font
				(size 1.27 1.27)
			)
			(justify left)
		)
		(property "Intersheetrefs" "${INTERSHEET_REFS}"
			(at -0.635 0.635 0)
			(effects
				(font
					(size 1.27 1.27)
				)
				(justify right)
				(hide yes)
			)
		)
	)
	(global_label "PCIE_HPM_RX[0]_P"
		(shape input)
		(at 198.12 237.49 180)
		(fields_autoplaced yes)
		(effects
			(font
				(size 1.27 1.27)
			)
			(justify right)
		)
		(property "Intersheetrefs" "${INTERSHEET_REFS}"
			(at 29.845 0.635 0)
			(effects
				(font
					(size 1.27 1.27)
				)
				(hide yes)
			)
		)
	)
	(global_label "RST_PLTRST_BUF_N_R"
		(shape input)
		(at 165.1 217.17 180)
		(fields_autoplaced yes)
		(effects
			(font
				(size 1.27 1.27)
			)
			(justify right)
		)
		(property "Intersheetrefs" "${INTERSHEET_REFS}"
			(at 128.905 -22.225 0)
			(effects
				(font
					(size 1.27 1.27)
				)
				(justify right)
				(hide yes)
			)
		)
	)
	(global_label "QSPI0_D3"
		(shape input)
		(at 231.14 118.11 0)
		(fields_autoplaced yes)
		(effects
			(font
				(size 1.27 1.27)
			)
			(justify left)
		)
		(property "Intersheetrefs" "${INTERSHEET_REFS}"
			(at -0.635 0.635 0)
			(effects
				(font
					(size 1.27 1.27)
				)
				(justify right)
				(hide yes)
			)
		)
	)
	(global_label "ESPI_CLK_1V8"
		(shape input)
		(at 231.14 80.01 0)
		(fields_autoplaced yes)
		(effects
			(font
				(size 1.27 1.27)
			)
			(justify left)
		)
		(property "Intersheetrefs" "${INTERSHEET_REFS}"
			(at -0.635 0.635 0)
			(effects
				(font
					(size 1.27 1.27)
				)
				(justify right)
				(hide yes)
			)
		)
	)
	(global_label "SGPIO_INTR_N"
		(shape input)
		(at 231.14 184.15 0)
		(fields_autoplaced yes)
		(effects
			(font
				(size 1.27 1.27)
			)
			(justify left)
		)
		(property "Intersheetrefs" "${INTERSHEET_REFS}"
			(at -0.635 0.635 0)
			(effects
				(font
					(size 1.27 1.27)
				)
				(justify right)
				(hide yes)
			)
		)
	)
	(global_label "PCIE_HPM_TX[3]_P"
		(shape input)
		(at 231.14 260.35 0)
		(fields_autoplaced yes)
		(effects
			(font
				(size 1.27 1.27)
			)
			(justify left)
		)
		(property "Intersheetrefs" "${INTERSHEET_REFS}"
			(at -0.635 0.635 0)
			(effects
				(font
					(size 1.27 1.27)
				)
				(justify right)
				(hide yes)
			)
		)
	)
	(global_label "PCIE_BMC_CLK_100_N"
		(shape input)
		(at 198.12 115.57 180)
		(fields_autoplaced yes)
		(effects
			(font
				(size 1.27 1.27)
			)
			(justify right)
		)
		(property "Intersheetrefs" "${INTERSHEET_REFS}"
			(at 29.845 0.635 0)
			(effects
				(font
					(size 1.27 1.27)
				)
				(hide yes)
			)
		)
	)
	(global_label "SPI0_CLK"
		(shape input)
		(at 300.99 53.34 0)
		(fields_autoplaced yes)
		(effects
			(font
				(size 1.27 1.27)
			)
			(justify left)
		)
		(property "Intersheetrefs" "${INTERSHEET_REFS}"
			(at 69.215 -10.795 0)
			(effects
				(font
					(size 1.27 1.27)
				)
				(justify right)
				(hide yes)
			)
		)
	)
	(global_label "I2C[6]_SCL"
		(shape input)
		(at 198.12 135.89 180)
		(fields_autoplaced yes)
		(effects
			(font
				(size 1.27 1.27)
			)
			(justify right)
		)
		(property "Intersheetrefs" "${INTERSHEET_REFS}"
			(at 29.845 0.635 0)
			(effects
				(font
					(size 1.27 1.27)
				)
				(hide yes)
			)
		)
	)
	(global_label "CHASI#_R"
		(shape input)
		(at 165.1 224.79 180)
		(fields_autoplaced yes)
		(effects
			(font
				(size 1.27 1.27)
			)
			(justify right)
		)
		(property "Intersheetrefs" "${INTERSHEET_REFS}"
			(at 128.905 -40.005 0)
			(effects
				(font
					(size 1.27 1.27)
				)
				(justify right)
				(hide yes)
			)
		)
	)
	(global_label "NCSI_RXD0"
		(shape input)
		(at 231.14 138.43 0)
		(fields_autoplaced yes)
		(effects
			(font
				(size 1.27 1.27)
			)
			(justify left)
		)
		(property "Intersheetrefs" "${INTERSHEET_REFS}"
			(at -0.635 0.635 0)
			(effects
				(font
					(size 1.27 1.27)
				)
				(justify right)
				(hide yes)
			)
		)
	)
	(global_label "PCIE_HPM_RX[0]_N"
		(shape input)
		(at 198.12 240.03 180)
		(fields_autoplaced yes)
		(effects
			(font
				(size 1.27 1.27)
			)
			(justify right)
		)
		(property "Intersheetrefs" "${INTERSHEET_REFS}"
			(at 29.845 0.635 0)
			(effects
				(font
					(size 1.27 1.27)
				)
				(hide yes)
			)
		)
	)
	(global_label "RSVD2"
		(shape input)
		(at 281.94 173.99 0)
		(fields_autoplaced yes)
		(effects
			(font
				(size 1.27 1.27)
			)
			(justify left)
		)
		(property "Intersheetrefs" "${INTERSHEET_REFS}"
			(at 576.58 6.35 0)
			(effects
				(font
					(size 1.27 1.27)
				)
				(hide yes)
			)
		)
	)
	(global_label "I3C[2]_SCL"
		(shape input)
		(at 187.96 59.69 180)
		(fields_autoplaced yes)
		(effects
			(font
				(size 1.27 1.27)
			)
			(justify right)
		)
		(property "Intersheetrefs" "${INTERSHEET_REFS}"
			(at 19.685 0.635 0)
			(effects
				(font
					(size 1.27 1.27)
				)
				(hide yes)
			)
		)
	)
	(global_label "PCIE_HPM_RX[3]_N"
		(shape input)
		(at 198.12 262.89 180)
		(fields_autoplaced yes)
		(effects
			(font
				(size 1.27 1.27)
			)
			(justify right)
		)
		(property "Intersheetrefs" "${INTERSHEET_REFS}"
			(at 29.845 0.635 0)
			(effects
				(font
					(size 1.27 1.27)
				)
				(hide yes)
			)
		)
	)
	(global_label "3V0_BAT"
		(shape input)
		(at 231.14 186.69 0)
		(fields_autoplaced yes)
		(effects
			(font
				(size 1.27 1.27)
			)
			(justify left)
		)
		(property "Intersheetrefs" "${INTERSHEET_REFS}"
			(at -0.635 0.635 0)
			(effects
				(font
					(size 1.27 1.27)
				)
				(justify right)
				(hide yes)
			)
		)
	)
	(global_label "SGPIO0_DI"
		(shape input)
		(at 231.14 161.29 0)
		(fields_autoplaced yes)
		(effects
			(font
				(size 1.27 1.27)
			)
			(justify left)
		)
		(property "Intersheetrefs" "${INTERSHEET_REFS}"
			(at -0.635 0.635 0)
			(effects
				(font
					(size 1.27 1.27)
				)
				(justify right)
				(hide yes)
			)
		)
	)
	(global_label "USB2_D_P"
		(shape input)
		(at 231.14 214.63 0)
		(fields_autoplaced yes)
		(effects
			(font
				(size 1.27 1.27)
			)
			(justify left)
		)
		(property "Intersheetrefs" "${INTERSHEET_REFS}"
			(at -0.635 0.635 0)
			(effects
				(font
					(size 1.27 1.27)
				)
				(justify right)
				(hide yes)
			)
		)
	)
	(global_label "QSPI1_CLK"
		(shape input)
		(at 231.14 196.85 0)
		(fields_autoplaced yes)
		(effects
			(font
				(size 1.27 1.27)
			)
			(justify left)
		)
		(property "Intersheetrefs" "${INTERSHEET_REFS}"
			(at -0.635 0.635 0)
			(effects
				(font
					(size 1.27 1.27)
				)
				(justify right)
				(hide yes)
			)
		)
	)
	(global_label "PCIE_HPM_TX[3]_N"
		(shape input)
		(at 231.14 262.89 0)
		(fields_autoplaced yes)
		(effects
			(font
				(size 1.27 1.27)
			)
			(justify left)
		)
		(property "Intersheetrefs" "${INTERSHEET_REFS}"
			(at -0.635 0.635 0)
			(effects
				(font
					(size 1.27 1.27)
				)
				(justify right)
				(hide yes)
			)
		)
	)
	(global_label "I2C[3]_SCL"
		(shape input)
		(at 198.12 95.25 180)
		(fields_autoplaced yes)
		(effects
			(font
				(size 1.27 1.27)
			)
			(justify right)
		)
		(property "Intersheetrefs" "${INTERSHEET_REFS}"
			(at 29.845 0.635 0)
			(effects
				(font
					(size 1.27 1.27)
				)
				(hide yes)
			)
		)
	)
	(global_label "I2C[4]_SCL"
		(shape input)
		(at 198.12 100.33 180)
		(fields_autoplaced yes)
		(effects
			(font
				(size 1.27 1.27)
			)
			(justify right)
		)
		(property "Intersheetrefs" "${INTERSHEET_REFS}"
			(at 29.845 0.635 0)
			(effects
				(font
					(size 1.27 1.27)
				)
				(hide yes)
			)
		)
	)
	(global_label "PCIE_BMC_RX_P"
		(shape input)
		(at 198.12 128.27 180)
		(fields_autoplaced yes)
		(effects
			(font
				(size 1.27 1.27)
			)
			(justify right)
		)
		(property "Intersheetrefs" "${INTERSHEET_REFS}"
			(at 29.845 0.635 0)
			(effects
				(font
					(size 1.27 1.27)
				)
				(hide yes)
			)
		)
	)
	(global_label "HPM_STBY_EN_R"
		(shape input)
		(at 165.1 201.93 180)
		(fields_autoplaced yes)
		(effects
			(font
				(size 1.27 1.27)
			)
			(justify right)
		)
		(property "Intersheetrefs" "${INTERSHEET_REFS}"
			(at 129.54 -73.025 0)
			(effects
				(font
					(size 1.27 1.27)
				)
				(justify right)
				(hide yes)
			)
		)
	)
	(symbol
		(lib_id "antmicroTestPoints:TP_1mm_SMD")
		(at 147.32 57.15 0)
		(mirror x)
		(unit 1)
		(exclude_from_sim no)
		(in_bom no)
		(on_board yes)
		(dnp no)
		(property "Reference" "TP10"
			(at 154.305 57.15 0)
			(effects
				(font
					(size 1.27 1.27)
				)
			)
		)
		(property "Value" "TP_1mm_SMD"
			(at 147.32 54.61 0)
			(effects
				(font
					(size 1.27 1.27)
				)
				(hide yes)
			)
		)
		(property "Footprint" "antmicro-footprints:TP_SMD_1mm"
			(at 162.56 46.99 0)
			(effects
				(font
					(size 1.27 1.27)
					(thickness 0.15)
				)
				(justify left bottom)
				(hide yes)
			)
		)
		(property "Datasheet" ""
			(at 162.56 44.45 0)
			(effects
				(font
					(size 1.27 1.27)
					(thickness 0.15)
				)
				(justify left bottom)
				(hide yes)
			)
		)
		(property "Description" "Test point 1mm SMD"
			(at 147.32 57.15 0)
			(effects
				(font
					(size 1.27 1.27)
				)
				(hide yes)
			)
		)
		(property "MPN" ""
			(at 147.32 57.15 0)
			(effects
				(font
					(size 1.27 1.27)
				)
				(hide yes)
			)
		)
		(property "Manufacturer" ""
			(at 147.32 57.15 0)
			(effects
				(font
					(size 1.27 1.27)
				)
				(hide yes)
			)
		)
		(property "Author" "Antmicro"
			(at 162.56 41.91 0)
			(effects
				(font
					(size 1.27 1.27)
					(thickness 0.15)
				)
				(justify left bottom)
				(hide yes)
			)
		)
		(property "License" "Apache-2.0"
			(at 162.56 39.37 0)
			(effects
				(font
					(size 1.27 1.27)
					(thickness 0.15)
				)
				(justify left bottom)
				(hide yes)
			)
		)
		(pin "1"
		)
		(instances
			(project "artix-dc-scm"
				(path ""
					(reference "TP10")
					(unit 1)
				)
			)
		)
	)
	(symbol
		(lib_id "antmicroTestPoints:TP_1mm_SMD")
		(at 147.32 59.69 0)
		(mirror x)
		(unit 1)
		(exclude_from_sim no)
		(in_bom no)
		(on_board yes)
		(dnp no)
		(property "Reference" "TP11"
			(at 154.305 59.69 0)
			(effects
				(font
					(size 1.27 1.27)
				)
			)
		)
		(property "Value" "TP_1mm_SMD"
			(at 147.32 57.15 0)
			(effects
				(font
					(size 1.27 1.27)
				)
				(hide yes)
			)
		)
		(property "Footprint" "antmicro-footprints:TP_SMD_1mm"
			(at 162.56 49.53 0)
			(effects
				(font
					(size 1.27 1.27)
					(thickness 0.15)
				)
				(justify left bottom)
				(hide yes)
			)
		)
		(property "Datasheet" ""
			(at 162.56 46.99 0)
			(effects
				(font
					(size 1.27 1.27)
					(thickness 0.15)
				)
				(justify left bottom)
				(hide yes)
			)
		)
		(property "Description" "Test point 1mm SMD"
			(at 147.32 59.69 0)
			(effects
				(font
					(size 1.27 1.27)
				)
				(hide yes)
			)
		)
		(property "MPN" ""
			(at 147.32 59.69 0)
			(effects
				(font
					(size 1.27 1.27)
				)
				(hide yes)
			)
		)
		(property "Manufacturer" ""
			(at 147.32 59.69 0)
			(effects
				(font
					(size 1.27 1.27)
				)
				(hide yes)
			)
		)
		(property "Author" "Antmicro"
			(at 162.56 44.45 0)
			(effects
				(font
					(size 1.27 1.27)
					(thickness 0.15)
				)
				(justify left bottom)
				(hide yes)
			)
		)
		(property "License" "Apache-2.0"
			(at 162.56 41.91 0)
			(effects
				(font
					(size 1.27 1.27)
					(thickness 0.15)
				)
				(justify left bottom)
				(hide yes)
			)
		)
		(pin "1"
		)
		(instances
			(project "artix-dc-scm"
				(path ""
					(reference "TP11")
					(unit 1)
				)
			)
		)
	)
	(symbol
		(lib_id "antmicroResistors0402:R_0R_0402")
		(at 257.81 171.45 0)
		(unit 1)
		(exclude_from_sim no)
		(in_bom yes)
		(on_board yes)
		(dnp no)
		(property "Reference" "R136"
			(at 255.27 170.18 0)
			(effects
				(font
					(size 1.27 1.27)
				)
			)
		)
		(property "Value" "R_0R_0402"
			(at 278.13 184.15 0)
			(effects
				(font
					(size 1.27 1.27)
					(thickness 0.15)
				)
				(justify left bottom)
				(hide yes)
			)
		)
		(property "Footprint" "antmicro-footprints:R_0402_1005Metric"
			(at 278.13 186.69 0)
			(effects
				(font
					(size 1.27 1.27)
					(thickness 0.15)
				)
				(justify left bottom)
				(hide yes)
			)
		)
		(property "Datasheet" "https://industrial.panasonic.com/cdbs/www-data/pdf/RDA0000/AOA0000C301.pdf"
			(at 278.13 189.23 0)
			(effects
				(font
					(size 1.27 1.27)
					(thickness 0.15)
				)
				(justify left bottom)
				(hide yes)
			)
		)
		(property "Description" "SMD Chip Resistor, Jumper, 0 ohm, 100 mW, 0402 [1005 Metric], Thick Film, General Purpose"
			(at 257.81 171.45 0)
			(effects
				(font
					(size 1.27 1.27)
				)
				(hide yes)
			)
		)
		(property "Manufacturer" "Panasonic"
			(at 278.13 194.31 0)
			(effects
				(font
					(size 1.27 1.27)
					(thickness 0.15)
				)
				(justify left bottom)
				(hide yes)
			)
		)
		(property "MPN" "ERJ2GE0R00X"
			(at 278.13 191.77 0)
			(effects
				(font
					(size 1.27 1.27)
					(thickness 0.15)
				)
				(justify left bottom)
				(hide yes)
			)
		)
		(property "Val" "0R"
			(at 264.795 170.18 0)
			(effects
				(font
					(size 1.27 1.27)
					(thickness 0.15)
				)
			)
		)
		(property "License" "Apache-2.0"
			(at 278.13 196.85 0)
			(effects
				(font
					(size 1.27 1.27)
					(thickness 0.15)
				)
				(justify left bottom)
				(hide yes)
			)
		)
		(property "Author" "Antmicro"
			(at 278.13 199.39 0)
			(effects
				(font
					(size 1.27 1.27)
					(thickness 0.15)
				)
				(justify left bottom)
				(hide yes)
			)
		)
		(property "Tolerance" "~"
			(at 278.13 181.61 0)
			(effects
				(font
					(size 1.27 1.27)
				)
				(justify left bottom)
				(hide yes)
			)
		)
		(property "Current" "1A"
			(at 260.35 167.005 0)
			(effects
				(font
					(size 1.27 1.27)
					(thickness 0.15)
				)
				(hide yes)
			)
		)
		(pin "1"
		)
		(pin "2"
		)
		(instances
			(project "artix-dc-scm"
				(path ""
					(reference "R136")
					(unit 1)
				)
			)
		)
	)
	(symbol
		(lib_id "antmicroResistors0402:R_0R_0402")
		(at 273.05 171.45 0)
		(unit 1)
		(exclude_from_sim no)
		(in_bom yes)
		(on_board yes)
		(dnp no)
		(property "Reference" "R137"
			(at 270.51 170.18 0)
			(effects
				(font
					(size 1.27 1.27)
				)
			)
		)
		(property "Value" "R_0R_0402"
			(at 293.37 184.15 0)
			(effects
				(font
					(size 1.27 1.27)
					(thickness 0.15)
				)
				(justify left bottom)
				(hide yes)
			)
		)
		(property "Footprint" "antmicro-footprints:R_0402_1005Metric"
			(at 293.37 186.69 0)
			(effects
				(font
					(size 1.27 1.27)
					(thickness 0.15)
				)
				(justify left bottom)
				(hide yes)
			)
		)
		(property "Datasheet" "https://industrial.panasonic.com/cdbs/www-data/pdf/RDA0000/AOA0000C301.pdf"
			(at 293.37 189.23 0)
			(effects
				(font
					(size 1.27 1.27)
					(thickness 0.15)
				)
				(justify left bottom)
				(hide yes)
			)
		)
		(property "Description" "SMD Chip Resistor, Jumper, 0 ohm, 100 mW, 0402 [1005 Metric], Thick Film, General Purpose"
			(at 273.05 171.45 0)
			(effects
				(font
					(size 1.27 1.27)
				)
				(hide yes)
			)
		)
		(property "Manufacturer" "Panasonic"
			(at 293.37 194.31 0)
			(effects
				(font
					(size 1.27 1.27)
					(thickness 0.15)
				)
				(justify left bottom)
				(hide yes)
			)
		)
		(property "MPN" "ERJ2GE0R00X"
			(at 293.37 191.77 0)
			(effects
				(font
					(size 1.27 1.27)
					(thickness 0.15)
				)
				(justify left bottom)
				(hide yes)
			)
		)
		(property "Val" "0R"
			(at 280.035 170.18 0)
			(effects
				(font
					(size 1.27 1.27)
					(thickness 0.15)
				)
			)
		)
		(property "License" "Apache-2.0"
			(at 293.37 196.85 0)
			(effects
				(font
					(size 1.27 1.27)
					(thickness 0.15)
				)
				(justify left bottom)
				(hide yes)
			)
		)
		(property "Author" "Antmicro"
			(at 293.37 199.39 0)
			(effects
				(font
					(size 1.27 1.27)
					(thickness 0.15)
				)
				(justify left bottom)
				(hide yes)
			)
		)
		(property "Tolerance" "~"
			(at 293.37 181.61 0)
			(effects
				(font
					(size 1.27 1.27)
				)
				(justify left bottom)
				(hide yes)
			)
		)
		(property "Current" "1A"
			(at 275.59 168.275 0)
			(effects
				(font
					(size 1.27 1.27)
					(thickness 0.15)
				)
				(hide yes)
			)
		)
		(pin "1"
		)
		(pin "2"
		)
		(instances
			(project "artix-dc-scm"
				(path ""
					(reference "R137")
					(unit 1)
				)
			)
		)
	)
	(symbol
		(lib_id "antmicropower:GND")
		(at 171.45 45.72 0)
		(unit 1)
		(exclude_from_sim no)
		(in_bom yes)
		(on_board yes)
		(dnp no)
		(property "Reference" "#PWR0191"
			(at 171.45 52.07 0)
			(effects
				(font
					(size 1.27 1.27)
				)
				(hide yes)
			)
		)
		(property "Value" "GND"
			(at 171.45 49.53 0)
			(effects
				(font
					(size 1.27 1.27)
				)
			)
		)
		(property "Footprint" ""
			(at 171.45 45.72 0)
			(effects
				(font
					(size 1.27 1.27)
				)
				(hide yes)
			)
		)
		(property "Datasheet" ""
			(at 171.45 45.72 0)
			(effects
				(font
					(size 1.27 1.27)
				)
				(hide yes)
			)
		)
		(property "Description" ""
			(at 171.45 45.72 0)
			(effects
				(font
					(size 1.27 1.27)
				)
				(hide yes)
			)
		)
		(property "Author" "Antmicro"
			(at 180.34 53.34 0)
			(effects
				(font
					(size 1.27 1.27)
					(thickness 0.15)
				)
				(justify left bottom)
				(hide yes)
			)
		)
		(property "License" "Apache-2.0"
			(at 180.34 55.88 0)
			(effects
				(font
					(size 1.27 1.27)
					(thickness 0.15)
				)
				(justify left bottom)
				(hide yes)
			)
		)
		(pin "1"
		)
		(instances
			(project "artix-dc-scm"
				(path ""
					(reference "#PWR0191")
					(unit 1)
				)
			)
		)
	)
	(symbol
		(lib_id "antmicroResistors0402:R_0R_0402")
		(at 292.1 64.77 0)
		(mirror y)
		(unit 1)
		(exclude_from_sim no)
		(in_bom yes)
		(on_board yes)
		(dnp no)
		(property "Reference" "R145"
			(at 284.48 63.5 0)
			(effects
				(font
					(size 1.27 1.27)
				)
			)
		)
		(property "Value" "R_0R_0402"
			(at 271.78 77.47 0)
			(effects
				(font
					(size 1.27 1.27)
					(thickness 0.15)
				)
				(justify left bottom)
				(hide yes)
			)
		)
		(property "Footprint" "antmicro-footprints:R_0402_1005Metric"
			(at 271.78 80.01 0)
			(effects
				(font
					(size 1.27 1.27)
					(thickness 0.15)
				)
				(justify left bottom)
				(hide yes)
			)
		)
		(property "Datasheet" "https://industrial.panasonic.com/cdbs/www-data/pdf/RDA0000/AOA0000C301.pdf"
			(at 271.78 82.55 0)
			(effects
				(font
					(size 1.27 1.27)
					(thickness 0.15)
				)
				(justify left bottom)
				(hide yes)
			)
		)
		(property "Description" "SMD Chip Resistor, Jumper, 0 ohm, 100 mW, 0402 [1005 Metric], Thick Film, General Purpose"
			(at 292.1 64.77 0)
			(effects
				(font
					(size 1.27 1.27)
				)
				(hide yes)
			)
		)
		(property "Manufacturer" "Panasonic"
			(at 271.78 87.63 0)
			(effects
				(font
					(size 1.27 1.27)
					(thickness 0.15)
				)
				(justify left bottom)
				(hide yes)
			)
		)
		(property "MPN" "ERJ2GE0R00X"
			(at 271.78 85.09 0)
			(effects
				(font
					(size 1.27 1.27)
					(thickness 0.15)
				)
				(justify left bottom)
				(hide yes)
			)
		)
		(property "Val" "0R"
			(at 293.37 63.5 0)
			(effects
				(font
					(size 1.27 1.27)
					(thickness 0.15)
				)
			)
		)
		(property "License" "Apache-2.0"
			(at 271.78 90.17 0)
			(effects
				(font
					(size 1.27 1.27)
					(thickness 0.15)
				)
				(justify left bottom)
				(hide yes)
			)
		)
		(property "Author" "Antmicro"
			(at 271.78 92.71 0)
			(effects
				(font
					(size 1.27 1.27)
					(thickness 0.15)
				)
				(justify left bottom)
				(hide yes)
			)
		)
		(property "Tolerance" "~"
			(at 271.78 74.93 0)
			(effects
				(font
					(size 1.27 1.27)
				)
				(justify left bottom)
				(hide yes)
			)
		)
		(property "Current" "1A"
			(at 349.885 76.2 0)
			(effects
				(font
					(size 1.27 1.27)
					(thickness 0.15)
				)
				(hide yes)
			)
		)
		(pin "1"
		)
		(pin "2"
		)
		(instances
			(project "artix-dc-scm"
				(path ""
					(reference "R145")
					(unit 1)
				)
			)
		)
	)
	(symbol
		(lib_id "antmicroPciConnectors:SFF-TA-1002-4C+")
		(at 201.93 39.37 0)
		(unit 1)
		(exclude_from_sim no)
		(in_bom no)
		(on_board yes)
		(dnp no)
		(fields_autoplaced yes)
		(property "Reference" "J9"
			(at 214.63 34.29 0)
			(effects
				(font
					(size 1.27 1.27)
					(thickness 0.15)
				)
			)
		)
		(property "Value" "SFF-TA-1002-4C+"
			(at 248.92 41.91 0)
			(effects
				(font
					(size 1.27 1.27)
					(thickness 0.15)
				)
				(justify left bottom)
				(hide yes)
			)
		)
		(property "Footprint" "antmicro-footprints:SFF-TA-1002-4C+"
			(at 248.92 44.45 0)
			(effects
				(font
					(size 1.27 1.27)
					(thickness 0.15)
				)
				(justify left bottom)
				(hide yes)
			)
		)
		(property "Datasheet" "https://cdn.amphenol-icc.com/media/wysiwyg/files/documentation/sme005.pdf?__cf_chl_jschl_tk__=4604d1306574a1ee474ea914090d3e0c57e266a6-1606907014-0-AbkYBTCTl__kMBcY3BDmgKpfUy32FqitwN2Lniuy8W-uyv2Ev04Q-Q5Mr7srIz_Wnur0_9chB4CRbxKSYcEh7IvAJYsUgJ0PWIS5YdRqqHg567uaZciEX2hQP4ss5l6M4XdNrxEjJppHvyRV3ku89t-VmUSzhgCb8oJlyHpTxST4dEmKZNXfM53TM0tmGirdVbCRt1Byrx5pkz_uMvNABIOj7B2-eDGK52J3DWRD76zEyjdxY7Iz11gPiOY5i_QGIR3uOwkR5LBPNXe8zGqAf8--AKa7RqDbIriQRt90_32C4zIuHqbGa05BXS135E65ov80PbVcb4eSiutCqcJUAacUwu3eVnXVeIumfihJxuP8Rv7_n6saeG_2IuQpEiskzovLGKZM3667Y-rm-AL1NRXTamtvBxqTk0vyMvZ60FgJ"
			(at 248.92 46.99 0)
			(effects
				(font
					(size 1.27 1.27)
					(thickness 0.15)
				)
				(justify left bottom)
				(hide yes)
			)
		)
		(property "Description" "PCB EDGE PCI connector"
			(at 201.93 39.37 0)
			(effects
				(font
					(size 1.27 1.27)
				)
				(hide yes)
			)
		)
		(property "MPN" ""
			(at 248.92 49.53 0)
			(effects
				(font
					(size 1.27 1.27)
					(thickness 0.15)
				)
				(justify left bottom)
			)
		)
		(property "Manufacturer" ""
			(at 248.92 52.07 0)
			(effects
				(font
					(size 1.27 1.27)
					(thickness 0.15)
				)
				(justify left bottom)
				(hide yes)
			)
		)
		(property "Author" "Antmicro"
			(at 248.92 54.61 0)
			(effects
				(font
					(size 1.27 1.27)
					(thickness 0.15)
				)
				(justify left bottom)
				(hide yes)
			)
		)
		(property "License" "Apache-2.0"
			(at 248.92 57.15 0)
			(effects
				(font
					(size 1.27 1.27)
					(thickness 0.15)
				)
				(justify left bottom)
				(hide yes)
			)
		)
		(property "DNP" ""
			(at 201.93 39.37 0)
			(effects
				(font
					(size 1.27 1.27)
				)
			)
		)
		(pin "B49"
		)
		(pin "B20"
		)
		(pin "OB7"
		)
		(pin "OA7"
		)
		(pin "A6"
		)
		(pin "B27"
		)
		(pin "B62"
		)
		(pin "B47"
		)
		(pin "A63"
		)
		(pin "B2"
		)
		(pin "B12"
		)
		(pin "OA2"
		)
		(pin "B61"
		)
		(pin "B34"
		)
		(pin "A68"
		)
		(pin "B30"
		)
		(pin "A58"
		)
		(pin "A69"
		)
		(pin "A61"
		)
		(pin "OA5"
		)
		(pin "B70"
		)
		(pin "B4"
		)
		(pin "A22"
		)
		(pin "A56"
		)
		(pin "A52"
		)
		(pin "OB14"
		)
		(pin "A35"
		)
		(pin "OB2"
		)
		(pin "A18"
		)
		(pin "A30"
		)
		(pin "B58"
		)
		(pin "B59"
		)
		(pin "B18"
		)
		(pin "B57"
		)
		(pin "A24"
		)
		(pin "OB12"
		)
		(pin "OB10"
		)
		(pin "A19"
		)
		(pin "A33"
		)
		(pin "A32"
		)
		(pin "A34"
		)
		(pin "A2"
		)
		(pin "B16"
		)
		(pin "B52"
		)
		(pin "A9"
		)
		(pin "A48"
		)
		(pin "A64"
		)
		(pin "OA14"
		)
		(pin "B5"
		)
		(pin "OB5"
		)
		(pin "B66"
		)
		(pin "OA6"
		)
		(pin "B7"
		)
		(pin "B64"
		)
		(pin "B68"
		)
		(pin "B46"
		)
		(pin "A65"
		)
		(pin "OA11"
		)
		(pin "B21"
		)
		(pin "B48"
		)
		(pin "B41"
		)
		(pin "B42"
		)
		(pin "B25"
		)
		(pin "OA12"
		)
		(pin "B6"
		)
		(pin "A8"
		)
		(pin "B26"
		)
		(pin "B40"
		)
		(pin "A27"
		)
		(pin "B29"
		)
		(pin "A57"
		)
		(pin "A21"
		)
		(pin "A47"
		)
		(pin "A5"
		)
		(pin "A46"
		)
		(pin "B28"
		)
		(pin "A60"
		)
		(pin "OB3"
		)
		(pin "B14"
		)
		(pin "A43"
		)
		(pin "OB9"
		)
		(pin "B9"
		)
		(pin "B35"
		)
		(pin "B1"
		)
		(pin "A45"
		)
		(pin "A36"
		)
		(pin "A7"
		)
		(pin "A70"
		)
		(pin "A40"
		)
		(pin "A38"
		)
		(pin "OA1"
		)
		(pin "B67"
		)
		(pin "OB8"
		)
		(pin "A3"
		)
		(pin "OA10"
		)
		(pin "A41"
		)
		(pin "B13"
		)
		(pin "B50"
		)
		(pin "A29"
		)
		(pin "B15"
		)
		(pin "B36"
		)
		(pin "B11"
		)
		(pin "OB6"
		)
		(pin "B65"
		)
		(pin "B44"
		)
		(pin "B69"
		)
		(pin "B54"
		)
		(pin "A26"
		)
		(pin "B45"
		)
		(pin "A16"
		)
		(pin "A39"
		)
		(pin "A49"
		)
		(pin "A44"
		)
		(pin "A59"
		)
		(pin "B23"
		)
		(pin "B8"
		)
		(pin "B24"
		)
		(pin "B38"
		)
		(pin "B43"
		)
		(pin "A37"
		)
		(pin "B37"
		)
		(pin "A42"
		)
		(pin "OA9"
		)
		(pin "B63"
		)
		(pin "OA13"
		)
		(pin "B53"
		)
		(pin "A66"
		)
		(pin "A67"
		)
		(pin "A51"
		)
		(pin "B55"
		)
		(pin "A54"
		)
		(pin "A17"
		)
		(pin "OB13"
		)
		(pin "B19"
		)
		(pin "B17"
		)
		(pin "A25"
		)
		(pin "A53"
		)
		(pin "A4"
		)
		(pin "OB4"
		)
		(pin "OA3"
		)
		(pin "OA4"
		)
		(pin "OA8"
		)
		(pin "B39"
		)
		(pin "B3"
		)
		(pin "A62"
		)
		(pin "A28"
		)
		(pin "B31"
		)
		(pin "B10"
		)
		(pin "B51"
		)
		(pin "B32"
		)
		(pin "B60"
		)
		(pin "B22"
		)
		(pin "OB1"
		)
		(pin "A55"
		)
		(pin "OB11"
		)
		(pin "B56"
		)
		(pin "A20"
		)
		(pin "A13"
		)
		(pin "A14"
		)
		(pin "A1"
		)
		(pin "A23"
		)
		(pin "A12"
		)
		(pin "A10"
		)
		(pin "A11"
		)
		(pin "A50"
		)
		(pin "A31"
		)
		(pin "A15"
		)
		(pin "B33"
		)
		(instances
			(project "artix-dc-scm"
				(path ""
					(reference "J9")
					(unit 1)
				)
			)
		)
	)
	(symbol
		(lib_id "antmicropower:GND")
		(at 171.45 266.7 0)
		(unit 1)
		(exclude_from_sim no)
		(in_bom yes)
		(on_board yes)
		(dnp no)
		(property "Reference" "#PWR0184"
			(at 171.45 273.05 0)
			(effects
				(font
					(size 1.27 1.27)
				)
				(hide yes)
			)
		)
		(property "Value" "GND"
			(at 171.45 270.51 0)
			(effects
				(font
					(size 1.27 1.27)
				)
			)
		)
		(property "Footprint" ""
			(at 171.45 266.7 0)
			(effects
				(font
					(size 1.27 1.27)
				)
				(hide yes)
			)
		)
		(property "Datasheet" ""
			(at 171.45 266.7 0)
			(effects
				(font
					(size 1.27 1.27)
				)
				(hide yes)
			)
		)
		(property "Description" ""
			(at 171.45 266.7 0)
			(effects
				(font
					(size 1.27 1.27)
				)
				(hide yes)
			)
		)
		(property "Author" "Antmicro"
			(at 180.34 274.32 0)
			(effects
				(font
					(size 1.27 1.27)
					(thickness 0.15)
				)
				(justify left bottom)
				(hide yes)
			)
		)
		(property "License" "Apache-2.0"
			(at 180.34 276.86 0)
			(effects
				(font
					(size 1.27 1.27)
					(thickness 0.15)
				)
				(justify left bottom)
				(hide yes)
			)
		)
		(pin "1"
		)
		(instances
			(project "artix-dc-scm"
				(path ""
					(reference "#PWR0184")
					(unit 1)
				)
			)
		)
	)
	(symbol
		(lib_id "antmicropower:GND")
		(at 171.45 186.69 0)
		(unit 1)
		(exclude_from_sim no)
		(in_bom yes)
		(on_board yes)
		(dnp no)
		(property "Reference" "#PWR094"
			(at 171.45 193.04 0)
			(effects
				(font
					(size 1.27 1.27)
				)
				(hide yes)
			)
		)
		(property "Value" "GND"
			(at 171.45 190.5 0)
			(effects
				(font
					(size 1.27 1.27)
				)
			)
		)
		(property "Footprint" ""
			(at 171.45 186.69 0)
			(effects
				(font
					(size 1.27 1.27)
				)
				(hide yes)
			)
		)
		(property "Datasheet" ""
			(at 171.45 186.69 0)
			(effects
				(font
					(size 1.27 1.27)
				)
				(hide yes)
			)
		)
		(property "Description" ""
			(at 171.45 186.69 0)
			(effects
				(font
					(size 1.27 1.27)
				)
				(hide yes)
			)
		)
		(property "Author" "Antmicro"
			(at 180.34 194.31 0)
			(effects
				(font
					(size 1.27 1.27)
					(thickness 0.15)
				)
				(justify left bottom)
				(hide yes)
			)
		)
		(property "License" "Apache-2.0"
			(at 180.34 196.85 0)
			(effects
				(font
					(size 1.27 1.27)
					(thickness 0.15)
				)
				(justify left bottom)
				(hide yes)
			)
		)
		(pin "1"
		)
		(instances
			(project "artix-dc-scm"
				(path ""
					(reference "#PWR094")
					(unit 1)
				)
			)
		)
	)
	(symbol
		(lib_id "antmicropower:GND")
		(at 257.81 266.7 0)
		(mirror y)
		(unit 1)
		(exclude_from_sim no)
		(in_bom yes)
		(on_board yes)
		(dnp no)
		(property "Reference" "#PWR095"
			(at 257.81 273.05 0)
			(effects
				(font
					(size 1.27 1.27)
				)
				(hide yes)
			)
		)
		(property "Value" "GND"
			(at 257.81 270.51 0)
			(effects
				(font
					(size 1.27 1.27)
				)
			)
		)
		(property "Footprint" ""
			(at 257.81 266.7 0)
			(effects
				(font
					(size 1.27 1.27)
				)
				(hide yes)
			)
		)
		(property "Datasheet" ""
			(at 257.81 266.7 0)
			(effects
				(font
					(size 1.27 1.27)
				)
				(hide yes)
			)
		)
		(property "Description" ""
			(at 257.81 266.7 0)
			(effects
				(font
					(size 1.27 1.27)
				)
				(hide yes)
			)
		)
		(property "Author" "Antmicro"
			(at 248.92 274.32 0)
			(effects
				(font
					(size 1.27 1.27)
					(thickness 0.15)
				)
				(justify left bottom)
				(hide yes)
			)
		)
		(property "License" "Apache-2.0"
			(at 248.92 276.86 0)
			(effects
				(font
					(size 1.27 1.27)
					(thickness 0.15)
				)
				(justify left bottom)
				(hide yes)
			)
		)
		(pin "1"
		)
		(instances
			(project "artix-dc-scm"
				(path ""
					(reference "#PWR095")
					(unit 1)
				)
			)
		)
	)
	(symbol
		(lib_id "antmicropower:GND")
		(at 252.73 160.02 0)
		(mirror y)
		(unit 1)
		(exclude_from_sim no)
		(in_bom yes)
		(on_board yes)
		(dnp no)
		(property "Reference" "#PWR0102"
			(at 252.73 166.37 0)
			(effects
				(font
					(size 1.27 1.27)
				)
				(hide yes)
			)
		)
		(property "Value" "GND"
			(at 252.73 163.83 0)
			(effects
				(font
					(size 1.27 1.27)
				)
			)
		)
		(property "Footprint" ""
			(at 252.73 160.02 0)
			(effects
				(font
					(size 1.27 1.27)
				)
				(hide yes)
			)
		)
		(property "Datasheet" ""
			(at 252.73 160.02 0)
			(effects
				(font
					(size 1.27 1.27)
				)
				(hide yes)
			)
		)
		(property "Description" ""
			(at 252.73 160.02 0)
			(effects
				(font
					(size 1.27 1.27)
				)
				(hide yes)
			)
		)
		(property "Author" "Antmicro"
			(at 243.84 167.64 0)
			(effects
				(font
					(size 1.27 1.27)
					(thickness 0.15)
				)
				(justify left bottom)
				(hide yes)
			)
		)
		(property "License" "Apache-2.0"
			(at 243.84 170.18 0)
			(effects
				(font
					(size 1.27 1.27)
					(thickness 0.15)
				)
				(justify left bottom)
				(hide yes)
			)
		)
		(pin "1"
		)
		(instances
			(project "artix-dc-scm"
				(path ""
					(reference "#PWR0102")
					(unit 1)
				)
			)
		)
	)
	(symbol
		(lib_id "antmicropower:GND")
		(at 262.89 48.26 0)
		(mirror y)
		(unit 1)
		(exclude_from_sim no)
		(in_bom yes)
		(on_board yes)
		(dnp no)
		(property "Reference" "#PWR0190"
			(at 262.89 54.61 0)
			(effects
				(font
					(size 1.27 1.27)
				)
				(hide yes)
			)
		)
		(property "Value" "GND"
			(at 262.89 52.07 0)
			(effects
				(font
					(size 1.27 1.27)
				)
			)
		)
		(property "Footprint" ""
			(at 262.89 48.26 0)
			(effects
				(font
					(size 1.27 1.27)
				)
				(hide yes)
			)
		)
		(property "Datasheet" ""
			(at 262.89 48.26 0)
			(effects
				(font
					(size 1.27 1.27)
				)
				(hide yes)
			)
		)
		(property "Description" ""
			(at 262.89 48.26 0)
			(effects
				(font
					(size 1.27 1.27)
				)
				(hide yes)
			)
		)
		(property "Author" "Antmicro"
			(at 254 55.88 0)
			(effects
				(font
					(size 1.27 1.27)
					(thickness 0.15)
				)
				(justify left bottom)
				(hide yes)
			)
		)
		(property "License" "Apache-2.0"
			(at 254 58.42 0)
			(effects
				(font
					(size 1.27 1.27)
					(thickness 0.15)
				)
				(justify left bottom)
				(hide yes)
			)
		)
		(pin "1"
		)
		(instances
			(project "artix-dc-scm"
				(path ""
					(reference "#PWR0190")
					(unit 1)
				)
			)
		)
	)
	(symbol
		(lib_id "antmicroResistors0402:R_0R_0402")
		(at 173.99 207.01 0)
		(unit 1)
		(exclude_from_sim no)
		(in_bom yes)
		(on_board yes)
		(dnp no)
		(property "Reference" "R103"
			(at 171.45 205.74 0)
			(effects
				(font
					(size 1.27 1.27)
				)
			)
		)
		(property "Value" "R_0R_0402"
			(at 194.31 219.71 0)
			(effects
				(font
					(size 1.27 1.27)
					(thickness 0.15)
				)
				(justify left bottom)
				(hide yes)
			)
		)
		(property "Footprint" "antmicro-footprints:R_0402_1005Metric"
			(at 194.31 222.25 0)
			(effects
				(font
					(size 1.27 1.27)
					(thickness 0.15)
				)
				(justify left bottom)
				(hide yes)
			)
		)
		(property "Datasheet" "https://industrial.panasonic.com/cdbs/www-data/pdf/RDA0000/AOA0000C301.pdf"
			(at 194.31 224.79 0)
			(effects
				(font
					(size 1.27 1.27)
					(thickness 0.15)
				)
				(justify left bottom)
				(hide yes)
			)
		)
		(property "Description" "SMD Chip Resistor, Jumper, 0 ohm, 100 mW, 0402 [1005 Metric], Thick Film, General Purpose"
			(at 173.99 207.01 0)
			(effects
				(font
					(size 1.27 1.27)
				)
				(hide yes)
			)
		)
		(property "Manufacturer" "Panasonic"
			(at 194.31 229.87 0)
			(effects
				(font
					(size 1.27 1.27)
					(thickness 0.15)
				)
				(justify left bottom)
				(hide yes)
			)
		)
		(property "MPN" "ERJ2GE0R00X"
			(at 194.31 227.33 0)
			(effects
				(font
					(size 1.27 1.27)
					(thickness 0.15)
				)
				(justify left bottom)
				(hide yes)
			)
		)
		(property "Val" "0R"
			(at 180.34 205.74 0)
			(effects
				(font
					(size 1.27 1.27)
					(thickness 0.15)
				)
			)
		)
		(property "License" "Apache-2.0"
			(at 194.31 232.41 0)
			(effects
				(font
					(size 1.27 1.27)
					(thickness 0.15)
				)
				(justify left bottom)
				(hide yes)
			)
		)
		(property "Author" "Antmicro"
			(at 194.31 234.95 0)
			(effects
				(font
					(size 1.27 1.27)
					(thickness 0.15)
				)
				(justify left bottom)
				(hide yes)
			)
		)
		(property "Tolerance" "~"
			(at 194.31 217.17 0)
			(effects
				(font
					(size 1.27 1.27)
				)
				(justify left bottom)
				(hide yes)
			)
		)
		(property "Current" "1A"
			(at 120.015 218.44 0)
			(effects
				(font
					(size 1.27 1.27)
					(thickness 0.15)
				)
				(hide yes)
			)
		)
		(pin "1"
		)
		(pin "2"
		)
		(instances
			(project "artix-dc-scm"
				(path ""
					(reference "R103")
					(unit 1)
				)
			)
		)
	)
	(symbol
		(lib_id "antmicropower:GND")
		(at 168.91 64.77 0)
		(unit 1)
		(exclude_from_sim no)
		(in_bom yes)
		(on_board yes)
		(dnp no)
		(property "Reference" "#PWR026"
			(at 168.91 71.12 0)
			(effects
				(font
					(size 1.27 1.27)
				)
				(hide yes)
			)
		)
		(property "Value" "GND"
			(at 168.91 68.58 0)
			(effects
				(font
					(size 1.27 1.27)
				)
			)
		)
		(property "Footprint" ""
			(at 168.91 64.77 0)
			(effects
				(font
					(size 1.27 1.27)
				)
				(hide yes)
			)
		)
		(property "Datasheet" ""
			(at 168.91 64.77 0)
			(effects
				(font
					(size 1.27 1.27)
				)
				(hide yes)
			)
		)
		(property "Description" ""
			(at 168.91 64.77 0)
			(effects
				(font
					(size 1.27 1.27)
				)
				(hide yes)
			)
		)
		(property "Author" "Antmicro"
			(at 177.8 72.39 0)
			(effects
				(font
					(size 1.27 1.27)
					(thickness 0.15)
				)
				(justify left bottom)
				(hide yes)
			)
		)
		(property "License" "Apache-2.0"
			(at 177.8 74.93 0)
			(effects
				(font
					(size 1.27 1.27)
					(thickness 0.15)
				)
				(justify left bottom)
				(hide yes)
			)
		)
		(pin "1"
		)
		(instances
			(project "artix-dc-scm"
				(path ""
					(reference "#PWR026")
					(unit 1)
				)
			)
		)
	)
	(symbol
		(lib_id "antmicroResistors0402:R_0R_0402")
		(at 173.99 212.09 0)
		(unit 1)
		(exclude_from_sim no)
		(in_bom yes)
		(on_board yes)
		(dnp no)
		(property "Reference" "R105"
			(at 171.45 210.82 0)
			(effects
				(font
					(size 1.27 1.27)
				)
			)
		)
		(property "Value" "R_0R_0402"
			(at 194.31 224.79 0)
			(effects
				(font
					(size 1.27 1.27)
					(thickness 0.15)
				)
				(justify left bottom)
				(hide yes)
			)
		)
		(property "Footprint" "antmicro-footprints:R_0402_1005Metric"
			(at 194.31 227.33 0)
			(effects
				(font
					(size 1.27 1.27)
					(thickness 0.15)
				)
				(justify left bottom)
				(hide yes)
			)
		)
		(property "Datasheet" "https://industrial.panasonic.com/cdbs/www-data/pdf/RDA0000/AOA0000C301.pdf"
			(at 194.31 229.87 0)
			(effects
				(font
					(size 1.27 1.27)
					(thickness 0.15)
				)
				(justify left bottom)
				(hide yes)
			)
		)
		(property "Description" "SMD Chip Resistor, Jumper, 0 ohm, 100 mW, 0402 [1005 Metric], Thick Film, General Purpose"
			(at 173.99 212.09 0)
			(effects
				(font
					(size 1.27 1.27)
				)
				(hide yes)
			)
		)
		(property "Manufacturer" "Panasonic"
			(at 194.31 234.95 0)
			(effects
				(font
					(size 1.27 1.27)
					(thickness 0.15)
				)
				(justify left bottom)
				(hide yes)
			)
		)
		(property "MPN" "ERJ2GE0R00X"
			(at 194.31 232.41 0)
			(effects
				(font
					(size 1.27 1.27)
					(thickness 0.15)
				)
				(justify left bottom)
				(hide yes)
			)
		)
		(property "Val" "0R"
			(at 180.34 210.82 0)
			(effects
				(font
					(size 1.27 1.27)
					(thickness 0.15)
				)
			)
		)
		(property "License" "Apache-2.0"
			(at 194.31 237.49 0)
			(effects
				(font
					(size 1.27 1.27)
					(thickness 0.15)
				)
				(justify left bottom)
				(hide yes)
			)
		)
		(property "Author" "Antmicro"
			(at 194.31 240.03 0)
			(effects
				(font
					(size 1.27 1.27)
					(thickness 0.15)
				)
				(justify left bottom)
				(hide yes)
			)
		)
		(property "Tolerance" "~"
			(at 194.31 222.25 0)
			(effects
				(font
					(size 1.27 1.27)
				)
				(justify left bottom)
				(hide yes)
			)
		)
		(property "Current" "1A"
			(at 122.555 224.155 0)
			(effects
				(font
					(size 1.27 1.27)
					(thickness 0.15)
				)
				(hide yes)
			)
		)
		(pin "1"
		)
		(pin "2"
		)
		(instances
			(project "artix-dc-scm"
				(path ""
					(reference "R105")
					(unit 1)
				)
			)
		)
	)
	(symbol
		(lib_id "antmicroResistors0402:R_0R_0402")
		(at 173.99 229.87 0)
		(unit 1)
		(exclude_from_sim no)
		(in_bom yes)
		(on_board yes)
		(dnp no)
		(property "Reference" "R112"
			(at 171.45 228.6 0)
			(effects
				(font
					(size 1.27 1.27)
				)
			)
		)
		(property "Value" "R_0R_0402"
			(at 194.31 242.57 0)
			(effects
				(font
					(size 1.27 1.27)
					(thickness 0.15)
				)
				(justify left bottom)
				(hide yes)
			)
		)
		(property "Footprint" "antmicro-footprints:R_0402_1005Metric"
			(at 194.31 245.11 0)
			(effects
				(font
					(size 1.27 1.27)
					(thickness 0.15)
				)
				(justify left bottom)
				(hide yes)
			)
		)
		(property "Datasheet" "https://industrial.panasonic.com/cdbs/www-data/pdf/RDA0000/AOA0000C301.pdf"
			(at 194.31 247.65 0)
			(effects
				(font
					(size 1.27 1.27)
					(thickness 0.15)
				)
				(justify left bottom)
				(hide yes)
			)
		)
		(property "Description" "SMD Chip Resistor, Jumper, 0 ohm, 100 mW, 0402 [1005 Metric], Thick Film, General Purpose"
			(at 173.99 229.87 0)
			(effects
				(font
					(size 1.27 1.27)
				)
				(hide yes)
			)
		)
		(property "Manufacturer" "Panasonic"
			(at 194.31 252.73 0)
			(effects
				(font
					(size 1.27 1.27)
					(thickness 0.15)
				)
				(justify left bottom)
				(hide yes)
			)
		)
		(property "MPN" "ERJ2GE0R00X"
			(at 194.31 250.19 0)
			(effects
				(font
					(size 1.27 1.27)
					(thickness 0.15)
				)
				(justify left bottom)
				(hide yes)
			)
		)
		(property "Val" "0R"
			(at 180.34 228.6 0)
			(effects
				(font
					(size 1.27 1.27)
					(thickness 0.15)
				)
			)
		)
		(property "License" "Apache-2.0"
			(at 194.31 255.27 0)
			(effects
				(font
					(size 1.27 1.27)
					(thickness 0.15)
				)
				(justify left bottom)
				(hide yes)
			)
		)
		(property "Author" "Antmicro"
			(at 194.31 257.81 0)
			(effects
				(font
					(size 1.27 1.27)
					(thickness 0.15)
				)
				(justify left bottom)
				(hide yes)
			)
		)
		(property "Tolerance" "~"
			(at 194.31 240.03 0)
			(effects
				(font
					(size 1.27 1.27)
				)
				(justify left bottom)
				(hide yes)
			)
		)
		(property "Current" "1A"
			(at 120.015 239.395 0)
			(effects
				(font
					(size 1.27 1.27)
					(thickness 0.15)
				)
				(hide yes)
			)
		)
		(pin "1"
		)
		(pin "2"
		)
		(instances
			(project "artix-dc-scm"
				(path ""
					(reference "R112")
					(unit 1)
				)
			)
		)
	)
	(symbol
		(lib_id "antmicroResistors0402:R_0R_0402")
		(at 292.1 69.85 0)
		(mirror y)
		(unit 1)
		(exclude_from_sim no)
		(in_bom yes)
		(on_board yes)
		(dnp no)
		(property "Reference" "R144"
			(at 284.48 68.58 0)
			(effects
				(font
					(size 1.27 1.27)
				)
			)
		)
		(property "Value" "R_0R_0402"
			(at 271.78 82.55 0)
			(effects
				(font
					(size 1.27 1.27)
					(thickness 0.15)
				)
				(justify left bottom)
				(hide yes)
			)
		)
		(property "Footprint" "antmicro-footprints:R_0402_1005Metric"
			(at 271.78 85.09 0)
			(effects
				(font
					(size 1.27 1.27)
					(thickness 0.15)
				)
				(justify left bottom)
				(hide yes)
			)
		)
		(property "Datasheet" "https://industrial.panasonic.com/cdbs/www-data/pdf/RDA0000/AOA0000C301.pdf"
			(at 271.78 87.63 0)
			(effects
				(font
					(size 1.27 1.27)
					(thickness 0.15)
				)
				(justify left bottom)
				(hide yes)
			)
		)
		(property "Description" "SMD Chip Resistor, Jumper, 0 ohm, 100 mW, 0402 [1005 Metric], Thick Film, General Purpose"
			(at 292.1 69.85 0)
			(effects
				(font
					(size 1.27 1.27)
				)
				(hide yes)
			)
		)
		(property "Manufacturer" "Panasonic"
			(at 271.78 92.71 0)
			(effects
				(font
					(size 1.27 1.27)
					(thickness 0.15)
				)
				(justify left bottom)
				(hide yes)
			)
		)
		(property "MPN" "ERJ2GE0R00X"
			(at 271.78 90.17 0)
			(effects
				(font
					(size 1.27 1.27)
					(thickness 0.15)
				)
				(justify left bottom)
				(hide yes)
			)
		)
		(property "Val" "0R"
			(at 293.37 68.58 0)
			(effects
				(font
					(size 1.27 1.27)
					(thickness 0.15)
				)
			)
		)
		(property "License" "Apache-2.0"
			(at 271.78 95.25 0)
			(effects
				(font
					(size 1.27 1.27)
					(thickness 0.15)
				)
				(justify left bottom)
				(hide yes)
			)
		)
		(property "Author" "Antmicro"
			(at 271.78 97.79 0)
			(effects
				(font
					(size 1.27 1.27)
					(thickness 0.15)
				)
				(justify left bottom)
				(hide yes)
			)
		)
		(property "Tolerance" "~"
			(at 271.78 80.01 0)
			(effects
				(font
					(size 1.27 1.27)
				)
				(justify left bottom)
				(hide yes)
			)
		)
		(property "Current" "1A"
			(at 289.56 66.04 0)
			(effects
				(font
					(size 1.27 1.27)
					(thickness 0.15)
				)
				(hide yes)
			)
		)
		(pin "1"
		)
		(pin "2"
		)
		(instances
			(project "artix-dc-scm"
				(path ""
					(reference "R144")
					(unit 1)
				)
			)
		)
	)
	(symbol
		(lib_id "antmicropower:GND")
		(at 171.45 134.62 0)
		(unit 1)
		(exclude_from_sim no)
		(in_bom yes)
		(on_board yes)
		(dnp no)
		(property "Reference" "#PWR097"
			(at 171.45 140.97 0)
			(effects
				(font
					(size 1.27 1.27)
				)
				(hide yes)
			)
		)
		(property "Value" "GND"
			(at 171.45 138.43 0)
			(effects
				(font
					(size 1.27 1.27)
				)
			)
		)
		(property "Footprint" ""
			(at 171.45 134.62 0)
			(effects
				(font
					(size 1.27 1.27)
				)
				(hide yes)
			)
		)
		(property "Datasheet" ""
			(at 171.45 134.62 0)
			(effects
				(font
					(size 1.27 1.27)
				)
				(hide yes)
			)
		)
		(property "Description" ""
			(at 171.45 134.62 0)
			(effects
				(font
					(size 1.27 1.27)
				)
				(hide yes)
			)
		)
		(property "Author" "Antmicro"
			(at 180.34 142.24 0)
			(effects
				(font
					(size 1.27 1.27)
					(thickness 0.15)
				)
				(justify left bottom)
				(hide yes)
			)
		)
		(property "License" "Apache-2.0"
			(at 180.34 144.78 0)
			(effects
				(font
					(size 1.27 1.27)
					(thickness 0.15)
				)
				(justify left bottom)
				(hide yes)
			)
		)
		(pin "1"
		)
		(instances
			(project "artix-dc-scm"
				(path ""
					(reference "#PWR097")
					(unit 1)
				)
			)
		)
	)
	(symbol
		(lib_id "antmicroResistors0402:R_0R_0402")
		(at 292.1 67.31 0)
		(mirror y)
		(unit 1)
		(exclude_from_sim no)
		(in_bom yes)
		(on_board yes)
		(dnp no)
		(property "Reference" "R146"
			(at 284.48 66.04 0)
			(effects
				(font
					(size 1.27 1.27)
				)
			)
		)
		(property "Value" "R_0R_0402"
			(at 271.78 80.01 0)
			(effects
				(font
					(size 1.27 1.27)
					(thickness 0.15)
				)
				(justify left bottom)
				(hide yes)
			)
		)
		(property "Footprint" "antmicro-footprints:R_0402_1005Metric"
			(at 271.78 82.55 0)
			(effects
				(font
					(size 1.27 1.27)
					(thickness 0.15)
				)
				(justify left bottom)
				(hide yes)
			)
		)
		(property "Datasheet" "https://industrial.panasonic.com/cdbs/www-data/pdf/RDA0000/AOA0000C301.pdf"
			(at 271.78 85.09 0)
			(effects
				(font
					(size 1.27 1.27)
					(thickness 0.15)
				)
				(justify left bottom)
				(hide yes)
			)
		)
		(property "Description" "SMD Chip Resistor, Jumper, 0 ohm, 100 mW, 0402 [1005 Metric], Thick Film, General Purpose"
			(at 292.1 67.31 0)
			(effects
				(font
					(size 1.27 1.27)
				)
				(hide yes)
			)
		)
		(property "Manufacturer" "Panasonic"
			(at 271.78 90.17 0)
			(effects
				(font
					(size 1.27 1.27)
					(thickness 0.15)
				)
				(justify left bottom)
				(hide yes)
			)
		)
		(property "MPN" "ERJ2GE0R00X"
			(at 271.78 87.63 0)
			(effects
				(font
					(size 1.27 1.27)
					(thickness 0.15)
				)
				(justify left bottom)
				(hide yes)
			)
		)
		(property "Val" "0R"
			(at 293.37 66.04 0)
			(effects
				(font
					(size 1.27 1.27)
					(thickness 0.15)
				)
			)
		)
		(property "License" "Apache-2.0"
			(at 271.78 92.71 0)
			(effects
				(font
					(size 1.27 1.27)
					(thickness 0.15)
				)
				(justify left bottom)
				(hide yes)
			)
		)
		(property "Author" "Antmicro"
			(at 271.78 95.25 0)
			(effects
				(font
					(size 1.27 1.27)
					(thickness 0.15)
				)
				(justify left bottom)
				(hide yes)
			)
		)
		(property "Tolerance" "~"
			(at 271.78 77.47 0)
			(effects
				(font
					(size 1.27 1.27)
				)
				(justify left bottom)
				(hide yes)
			)
		)
		(property "Current" "1A"
			(at 341.63 78.105 0)
			(effects
				(font
					(size 1.27 1.27)
					(thickness 0.15)
				)
				(hide yes)
			)
		)
		(pin "1"
		)
		(pin "2"
		)
		(instances
			(project "artix-dc-scm"
				(path ""
					(reference "R146")
					(unit 1)
				)
			)
		)
	)
	(symbol
		(lib_id "antmicropower:GND")
		(at 252.73 104.14 0)
		(mirror y)
		(unit 1)
		(exclude_from_sim no)
		(in_bom yes)
		(on_board yes)
		(dnp no)
		(property "Reference" "#PWR0187"
			(at 252.73 110.49 0)
			(effects
				(font
					(size 1.27 1.27)
				)
				(hide yes)
			)
		)
		(property "Value" "GND"
			(at 252.73 107.95 0)
			(effects
				(font
					(size 1.27 1.27)
				)
			)
		)
		(property "Footprint" ""
			(at 252.73 104.14 0)
			(effects
				(font
					(size 1.27 1.27)
				)
				(hide yes)
			)
		)
		(property "Datasheet" ""
			(at 252.73 104.14 0)
			(effects
				(font
					(size 1.27 1.27)
				)
				(hide yes)
			)
		)
		(property "Description" ""
			(at 252.73 104.14 0)
			(effects
				(font
					(size 1.27 1.27)
				)
				(hide yes)
			)
		)
		(property "Author" "Antmicro"
			(at 243.84 111.76 0)
			(effects
				(font
					(size 1.27 1.27)
					(thickness 0.15)
				)
				(justify left bottom)
				(hide yes)
			)
		)
		(property "License" "Apache-2.0"
			(at 243.84 114.3 0)
			(effects
				(font
					(size 1.27 1.27)
					(thickness 0.15)
				)
				(justify left bottom)
				(hide yes)
			)
		)
		(pin "1"
		)
		(instances
			(project "artix-dc-scm"
				(path ""
					(reference "#PWR0187")
					(unit 1)
				)
			)
		)
	)
	(symbol
		(lib_id "antmicropower:GND")
		(at 252.73 144.78 0)
		(mirror y)
		(unit 1)
		(exclude_from_sim no)
		(in_bom yes)
		(on_board yes)
		(dnp no)
		(property "Reference" "#PWR0185"
			(at 252.73 151.13 0)
			(effects
				(font
					(size 1.27 1.27)
				)
				(hide yes)
			)
		)
		(property "Value" "GND"
			(at 252.73 148.59 0)
			(effects
				(font
					(size 1.27 1.27)
				)
			)
		)
		(property "Footprint" ""
			(at 252.73 144.78 0)
			(effects
				(font
					(size 1.27 1.27)
				)
				(hide yes)
			)
		)
		(property "Datasheet" ""
			(at 252.73 144.78 0)
			(effects
				(font
					(size 1.27 1.27)
				)
				(hide yes)
			)
		)
		(property "Description" ""
			(at 252.73 144.78 0)
			(effects
				(font
					(size 1.27 1.27)
				)
				(hide yes)
			)
		)
		(property "Author" "Antmicro"
			(at 243.84 152.4 0)
			(effects
				(font
					(size 1.27 1.27)
					(thickness 0.15)
				)
				(justify left bottom)
				(hide yes)
			)
		)
		(property "License" "Apache-2.0"
			(at 243.84 154.94 0)
			(effects
				(font
					(size 1.27 1.27)
					(thickness 0.15)
				)
				(justify left bottom)
				(hide yes)
			)
		)
		(pin "1"
		)
		(instances
			(project "artix-dc-scm"
				(path ""
					(reference "#PWR0185")
					(unit 1)
				)
			)
		)
	)
	(symbol
		(lib_id "antmicropower:GND")
		(at 257.81 213.36 0)
		(mirror y)
		(unit 1)
		(exclude_from_sim no)
		(in_bom yes)
		(on_board yes)
		(dnp no)
		(property "Reference" "#PWR099"
			(at 257.81 219.71 0)
			(effects
				(font
					(size 1.27 1.27)
				)
				(hide yes)
			)
		)
		(property "Value" "GND"
			(at 257.81 217.17 0)
			(effects
				(font
					(size 1.27 1.27)
				)
			)
		)
		(property "Footprint" ""
			(at 257.81 213.36 0)
			(effects
				(font
					(size 1.27 1.27)
				)
				(hide yes)
			)
		)
		(property "Datasheet" ""
			(at 257.81 213.36 0)
			(effects
				(font
					(size 1.27 1.27)
				)
				(hide yes)
			)
		)
		(property "Description" ""
			(at 257.81 213.36 0)
			(effects
				(font
					(size 1.27 1.27)
				)
				(hide yes)
			)
		)
		(property "Author" "Antmicro"
			(at 248.92 220.98 0)
			(effects
				(font
					(size 1.27 1.27)
					(thickness 0.15)
				)
				(justify left bottom)
				(hide yes)
			)
		)
		(property "License" "Apache-2.0"
			(at 248.92 223.52 0)
			(effects
				(font
					(size 1.27 1.27)
					(thickness 0.15)
				)
				(justify left bottom)
				(hide yes)
			)
		)
		(pin "1"
		)
		(instances
			(project "artix-dc-scm"
				(path ""
					(reference "#PWR099")
					(unit 1)
				)
			)
		)
	)
	(symbol
		(lib_id "antmicropower:GND")
		(at 252.73 180.34 0)
		(mirror y)
		(unit 1)
		(exclude_from_sim no)
		(in_bom yes)
		(on_board yes)
		(dnp no)
		(property "Reference" "#PWR0101"
			(at 252.73 186.69 0)
			(effects
				(font
					(size 1.27 1.27)
				)
				(hide yes)
			)
		)
		(property "Value" "GND"
			(at 252.73 184.15 0)
			(effects
				(font
					(size 1.27 1.27)
				)
			)
		)
		(property "Footprint" ""
			(at 252.73 180.34 0)
			(effects
				(font
					(size 1.27 1.27)
				)
				(hide yes)
			)
		)
		(property "Datasheet" ""
			(at 252.73 180.34 0)
			(effects
				(font
					(size 1.27 1.27)
				)
				(hide yes)
			)
		)
		(property "Description" ""
			(at 252.73 180.34 0)
			(effects
				(font
					(size 1.27 1.27)
				)
				(hide yes)
			)
		)
		(property "Author" "Antmicro"
			(at 243.84 187.96 0)
			(effects
				(font
					(size 1.27 1.27)
					(thickness 0.15)
				)
				(justify left bottom)
				(hide yes)
			)
		)
		(property "License" "Apache-2.0"
			(at 243.84 190.5 0)
			(effects
				(font
					(size 1.27 1.27)
					(thickness 0.15)
				)
				(justify left bottom)
				(hide yes)
			)
		)
		(pin "1"
		)
		(instances
			(project "artix-dc-scm"
				(path ""
					(reference "#PWR0101")
					(unit 1)
				)
			)
		)
	)
	(symbol
		(lib_id "antmicroResistors0402:R_0R_0402")
		(at 173.99 214.63 0)
		(unit 1)
		(exclude_from_sim no)
		(in_bom yes)
		(on_board yes)
		(dnp no)
		(property "Reference" "R106"
			(at 171.45 213.36 0)
			(effects
				(font
					(size 1.27 1.27)
				)
			)
		)
		(property "Value" "R_0R_0402"
			(at 194.31 227.33 0)
			(effects
				(font
					(size 1.27 1.27)
					(thickness 0.15)
				)
				(justify left bottom)
				(hide yes)
			)
		)
		(property "Footprint" "antmicro-footprints:R_0402_1005Metric"
			(at 194.31 229.87 0)
			(effects
				(font
					(size 1.27 1.27)
					(thickness 0.15)
				)
				(justify left bottom)
				(hide yes)
			)
		)
		(property "Datasheet" "https://industrial.panasonic.com/cdbs/www-data/pdf/RDA0000/AOA0000C301.pdf"
			(at 194.31 232.41 0)
			(effects
				(font
					(size 1.27 1.27)
					(thickness 0.15)
				)
				(justify left bottom)
				(hide yes)
			)
		)
		(property "Description" "SMD Chip Resistor, Jumper, 0 ohm, 100 mW, 0402 [1005 Metric], Thick Film, General Purpose"
			(at 173.99 214.63 0)
			(effects
				(font
					(size 1.27 1.27)
				)
				(hide yes)
			)
		)
		(property "Manufacturer" "Panasonic"
			(at 194.31 237.49 0)
			(effects
				(font
					(size 1.27 1.27)
					(thickness 0.15)
				)
				(justify left bottom)
				(hide yes)
			)
		)
		(property "MPN" "ERJ2GE0R00X"
			(at 194.31 234.95 0)
			(effects
				(font
					(size 1.27 1.27)
					(thickness 0.15)
				)
				(justify left bottom)
				(hide yes)
			)
		)
		(property "Val" "0R"
			(at 180.34 213.36 0)
			(effects
				(font
					(size 1.27 1.27)
					(thickness 0.15)
				)
			)
		)
		(property "License" "Apache-2.0"
			(at 194.31 240.03 0)
			(effects
				(font
					(size 1.27 1.27)
					(thickness 0.15)
				)
				(justify left bottom)
				(hide yes)
			)
		)
		(property "Author" "Antmicro"
			(at 194.31 242.57 0)
			(effects
				(font
					(size 1.27 1.27)
					(thickness 0.15)
				)
				(justify left bottom)
				(hide yes)
			)
		)
		(property "Tolerance" "~"
			(at 194.31 224.79 0)
			(effects
				(font
					(size 1.27 1.27)
				)
				(justify left bottom)
				(hide yes)
			)
		)
		(property "Current" "1A"
			(at 123.19 227.965 0)
			(effects
				(font
					(size 1.27 1.27)
					(thickness 0.15)
				)
				(hide yes)
			)
		)
		(pin "1"
		)
		(pin "2"
		)
		(instances
			(project "artix-dc-scm"
				(path ""
					(reference "R106")
					(unit 1)
				)
			)
		)
	)
	(symbol
		(lib_id "antmicroResistors0402:R_0R_0402")
		(at 173.99 201.93 0)
		(unit 1)
		(exclude_from_sim no)
		(in_bom yes)
		(on_board yes)
		(dnp no)
		(property "Reference" "R116"
			(at 171.45 200.66 0)
			(effects
				(font
					(size 1.27 1.27)
				)
			)
		)
		(property "Value" "R_0R_0402"
			(at 194.31 214.63 0)
			(effects
				(font
					(size 1.27 1.27)
					(thickness 0.15)
				)
				(justify left bottom)
				(hide yes)
			)
		)
		(property "Footprint" "antmicro-footprints:R_0402_1005Metric"
			(at 194.31 217.17 0)
			(effects
				(font
					(size 1.27 1.27)
					(thickness 0.15)
				)
				(justify left bottom)
				(hide yes)
			)
		)
		(property "Datasheet" "https://industrial.panasonic.com/cdbs/www-data/pdf/RDA0000/AOA0000C301.pdf"
			(at 194.31 219.71 0)
			(effects
				(font
					(size 1.27 1.27)
					(thickness 0.15)
				)
				(justify left bottom)
				(hide yes)
			)
		)
		(property "Description" "SMD Chip Resistor, Jumper, 0 ohm, 100 mW, 0402 [1005 Metric], Thick Film, General Purpose"
			(at 173.99 201.93 0)
			(effects
				(font
					(size 1.27 1.27)
				)
				(hide yes)
			)
		)
		(property "Manufacturer" "Panasonic"
			(at 194.31 224.79 0)
			(effects
				(font
					(size 1.27 1.27)
					(thickness 0.15)
				)
				(justify left bottom)
				(hide yes)
			)
		)
		(property "MPN" "ERJ2GE0R00X"
			(at 194.31 222.25 0)
			(effects
				(font
					(size 1.27 1.27)
					(thickness 0.15)
				)
				(justify left bottom)
				(hide yes)
			)
		)
		(property "Val" "0R"
			(at 180.34 200.66 0)
			(effects
				(font
					(size 1.27 1.27)
					(thickness 0.15)
				)
			)
		)
		(property "License" "Apache-2.0"
			(at 194.31 227.33 0)
			(effects
				(font
					(size 1.27 1.27)
					(thickness 0.15)
				)
				(justify left bottom)
				(hide yes)
			)
		)
		(property "Author" "Antmicro"
			(at 194.31 229.87 0)
			(effects
				(font
					(size 1.27 1.27)
					(thickness 0.15)
				)
				(justify left bottom)
				(hide yes)
			)
		)
		(property "Tolerance" "~"
			(at 194.31 212.09 0)
			(effects
				(font
					(size 1.27 1.27)
				)
				(justify left bottom)
				(hide yes)
			)
		)
		(property "Current" "1A"
			(at 120.65 203.2 0)
			(effects
				(font
					(size 1.27 1.27)
					(thickness 0.15)
				)
				(hide yes)
			)
		)
		(pin "1"
		)
		(pin "2"
		)
		(instances
			(project "artix-dc-scm"
				(path ""
					(reference "R116")
					(unit 1)
				)
			)
		)
	)
	(symbol
		(lib_id "antmicroResistors0402:R_0R_0402")
		(at 179.07 219.71 0)
		(mirror y)
		(unit 1)
		(exclude_from_sim no)
		(in_bom yes)
		(on_board yes)
		(dnp no)
		(property "Reference" "R108"
			(at 171.45 218.44 0)
			(effects
				(font
					(size 1.27 1.27)
				)
			)
		)
		(property "Value" "R_0R_0402"
			(at 158.75 232.41 0)
			(effects
				(font
					(size 1.27 1.27)
					(thickness 0.15)
				)
				(justify left bottom)
				(hide yes)
			)
		)
		(property "Footprint" "antmicro-footprints:R_0402_1005Metric"
			(at 158.75 234.95 0)
			(effects
				(font
					(size 1.27 1.27)
					(thickness 0.15)
				)
				(justify left bottom)
				(hide yes)
			)
		)
		(property "Datasheet" "https://industrial.panasonic.com/cdbs/www-data/pdf/RDA0000/AOA0000C301.pdf"
			(at 158.75 237.49 0)
			(effects
				(font
					(size 1.27 1.27)
					(thickness 0.15)
				)
				(justify left bottom)
				(hide yes)
			)
		)
		(property "Description" "SMD Chip Resistor, Jumper, 0 ohm, 100 mW, 0402 [1005 Metric], Thick Film, General Purpose"
			(at 179.07 219.71 0)
			(effects
				(font
					(size 1.27 1.27)
				)
				(hide yes)
			)
		)
		(property "Manufacturer" "Panasonic"
			(at 158.75 242.57 0)
			(effects
				(font
					(size 1.27 1.27)
					(thickness 0.15)
				)
				(justify left bottom)
				(hide yes)
			)
		)
		(property "MPN" "ERJ2GE0R00X"
			(at 158.75 240.03 0)
			(effects
				(font
					(size 1.27 1.27)
					(thickness 0.15)
				)
				(justify left bottom)
				(hide yes)
			)
		)
		(property "Val" "0R"
			(at 180.975 218.44 0)
			(effects
				(font
					(size 1.27 1.27)
					(thickness 0.15)
				)
			)
		)
		(property "License" "Apache-2.0"
			(at 158.75 245.11 0)
			(effects
				(font
					(size 1.27 1.27)
					(thickness 0.15)
				)
				(justify left bottom)
				(hide yes)
			)
		)
		(property "Author" "Antmicro"
			(at 158.75 247.65 0)
			(effects
				(font
					(size 1.27 1.27)
					(thickness 0.15)
				)
				(justify left bottom)
				(hide yes)
			)
		)
		(property "Tolerance" "~"
			(at 158.75 229.87 0)
			(effects
				(font
					(size 1.27 1.27)
				)
				(justify left bottom)
				(hide yes)
			)
		)
		(property "Current" "1A"
			(at 231.775 230.505 0)
			(effects
				(font
					(size 1.27 1.27)
					(thickness 0.15)
				)
				(hide yes)
			)
		)
		(pin "1"
		)
		(pin "2"
		)
		(instances
			(project "artix-dc-scm"
				(path ""
					(reference "R108")
					(unit 1)
				)
			)
		)
	)
	(symbol
		(lib_id "antmicroResistors0402:R_0R_0402")
		(at 173.99 199.39 0)
		(unit 1)
		(exclude_from_sim no)
		(in_bom yes)
		(on_board yes)
		(dnp no)
		(property "Reference" "R154"
			(at 171.45 198.12 0)
			(effects
				(font
					(size 1.27 1.27)
				)
			)
		)
		(property "Value" "R_0R_0402"
			(at 194.31 212.09 0)
			(effects
				(font
					(size 1.27 1.27)
					(thickness 0.15)
				)
				(justify left bottom)
				(hide yes)
			)
		)
		(property "Footprint" "antmicro-footprints:R_0402_1005Metric"
			(at 194.31 214.63 0)
			(effects
				(font
					(size 1.27 1.27)
					(thickness 0.15)
				)
				(justify left bottom)
				(hide yes)
			)
		)
		(property "Datasheet" "https://industrial.panasonic.com/cdbs/www-data/pdf/RDA0000/AOA0000C301.pdf"
			(at 194.31 217.17 0)
			(effects
				(font
					(size 1.27 1.27)
					(thickness 0.15)
				)
				(justify left bottom)
				(hide yes)
			)
		)
		(property "Description" "SMD Chip Resistor, Jumper, 0 ohm, 100 mW, 0402 [1005 Metric], Thick Film, General Purpose"
			(at 173.99 199.39 0)
			(effects
				(font
					(size 1.27 1.27)
				)
				(hide yes)
			)
		)
		(property "Manufacturer" "Panasonic"
			(at 194.31 222.25 0)
			(effects
				(font
					(size 1.27 1.27)
					(thickness 0.15)
				)
				(justify left bottom)
				(hide yes)
			)
		)
		(property "MPN" "ERJ2GE0R00X"
			(at 194.31 219.71 0)
			(effects
				(font
					(size 1.27 1.27)
					(thickness 0.15)
				)
				(justify left bottom)
				(hide yes)
			)
		)
		(property "Val" "0R"
			(at 180.34 198.12 0)
			(effects
				(font
					(size 1.27 1.27)
					(thickness 0.15)
				)
			)
		)
		(property "License" "Apache-2.0"
			(at 194.31 224.79 0)
			(effects
				(font
					(size 1.27 1.27)
					(thickness 0.15)
				)
				(justify left bottom)
				(hide yes)
			)
		)
		(property "Author" "Antmicro"
			(at 194.31 227.33 0)
			(effects
				(font
					(size 1.27 1.27)
					(thickness 0.15)
				)
				(justify left bottom)
				(hide yes)
			)
		)
		(property "Tolerance" "~"
			(at 194.31 209.55 0)
			(effects
				(font
					(size 1.27 1.27)
				)
				(justify left bottom)
				(hide yes)
			)
		)
		(property "Current" "1A"
			(at 120.65 212.09 0)
			(effects
				(font
					(size 1.27 1.27)
					(thickness 0.15)
				)
				(hide yes)
			)
		)
		(pin "1"
		)
		(pin "2"
		)
		(instances
			(project "artix-dc-scm"
				(path ""
					(reference "R154")
					(unit 1)
				)
			)
		)
	)
	(symbol
		(lib_id "antmicroResistors0402:R_0R_0402")
		(at 173.99 217.17 0)
		(unit 1)
		(exclude_from_sim no)
		(in_bom yes)
		(on_board yes)
		(dnp no)
		(property "Reference" "R107"
			(at 171.45 215.9 0)
			(effects
				(font
					(size 1.27 1.27)
				)
			)
		)
		(property "Value" "R_0R_0402"
			(at 194.31 229.87 0)
			(effects
				(font
					(size 1.27 1.27)
					(thickness 0.15)
				)
				(justify left bottom)
				(hide yes)
			)
		)
		(property "Footprint" "antmicro-footprints:R_0402_1005Metric"
			(at 194.31 232.41 0)
			(effects
				(font
					(size 1.27 1.27)
					(thickness 0.15)
				)
				(justify left bottom)
				(hide yes)
			)
		)
		(property "Datasheet" "https://industrial.panasonic.com/cdbs/www-data/pdf/RDA0000/AOA0000C301.pdf"
			(at 194.31 234.95 0)
			(effects
				(font
					(size 1.27 1.27)
					(thickness 0.15)
				)
				(justify left bottom)
				(hide yes)
			)
		)
		(property "Description" "SMD Chip Resistor, Jumper, 0 ohm, 100 mW, 0402 [1005 Metric], Thick Film, General Purpose"
			(at 173.99 217.17 0)
			(effects
				(font
					(size 1.27 1.27)
				)
				(hide yes)
			)
		)
		(property "Manufacturer" "Panasonic"
			(at 194.31 240.03 0)
			(effects
				(font
					(size 1.27 1.27)
					(thickness 0.15)
				)
				(justify left bottom)
				(hide yes)
			)
		)
		(property "MPN" "ERJ2GE0R00X"
			(at 194.31 237.49 0)
			(effects
				(font
					(size 1.27 1.27)
					(thickness 0.15)
				)
				(justify left bottom)
				(hide yes)
			)
		)
		(property "Val" "0R"
			(at 180.34 215.9 0)
			(effects
				(font
					(size 1.27 1.27)
					(thickness 0.15)
				)
			)
		)
		(property "License" "Apache-2.0"
			(at 194.31 242.57 0)
			(effects
				(font
					(size 1.27 1.27)
					(thickness 0.15)
				)
				(justify left bottom)
				(hide yes)
			)
		)
		(property "Author" "Antmicro"
			(at 194.31 245.11 0)
			(effects
				(font
					(size 1.27 1.27)
					(thickness 0.15)
				)
				(justify left bottom)
				(hide yes)
			)
		)
		(property "Tolerance" "~"
			(at 194.31 227.33 0)
			(effects
				(font
					(size 1.27 1.27)
				)
				(justify left bottom)
				(hide yes)
			)
		)
		(property "Current" "1A"
			(at 116.84 229.235 0)
			(effects
				(font
					(size 1.27 1.27)
					(thickness 0.15)
				)
				(hide yes)
			)
		)
		(pin "1"
		)
		(pin "2"
		)
		(instances
			(project "artix-dc-scm"
				(path ""
					(reference "R107")
					(unit 1)
				)
			)
		)
	)
	(symbol
		(lib_id "antmicropower:GND")
		(at 252.73 121.92 0)
		(mirror y)
		(unit 1)
		(exclude_from_sim no)
		(in_bom yes)
		(on_board yes)
		(dnp no)
		(property "Reference" "#PWR0186"
			(at 252.73 128.27 0)
			(effects
				(font
					(size 1.27 1.27)
				)
				(hide yes)
			)
		)
		(property "Value" "GND"
			(at 252.73 125.73 0)
			(effects
				(font
					(size 1.27 1.27)
				)
			)
		)
		(property "Footprint" ""
			(at 252.73 121.92 0)
			(effects
				(font
					(size 1.27 1.27)
				)
				(hide yes)
			)
		)
		(property "Datasheet" ""
			(at 252.73 121.92 0)
			(effects
				(font
					(size 1.27 1.27)
				)
				(hide yes)
			)
		)
		(property "Description" ""
			(at 252.73 121.92 0)
			(effects
				(font
					(size 1.27 1.27)
				)
				(hide yes)
			)
		)
		(property "Author" "Antmicro"
			(at 243.84 129.54 0)
			(effects
				(font
					(size 1.27 1.27)
					(thickness 0.15)
				)
				(justify left bottom)
				(hide yes)
			)
		)
		(property "License" "Apache-2.0"
			(at 243.84 132.08 0)
			(effects
				(font
					(size 1.27 1.27)
					(thickness 0.15)
				)
				(justify left bottom)
				(hide yes)
			)
		)
		(pin "1"
		)
		(instances
			(project "artix-dc-scm"
				(path ""
					(reference "#PWR0186")
					(unit 1)
				)
			)
		)
	)
	(symbol
		(lib_id "antmicroResistors0402:R_0R_0402")
		(at 173.99 209.55 0)
		(unit 1)
		(exclude_from_sim no)
		(in_bom yes)
		(on_board yes)
		(dnp no)
		(property "Reference" "R104"
			(at 171.45 208.28 0)
			(effects
				(font
					(size 1.27 1.27)
				)
			)
		)
		(property "Value" "R_0R_0402"
			(at 194.31 222.25 0)
			(effects
				(font
					(size 1.27 1.27)
					(thickness 0.15)
				)
				(justify left bottom)
				(hide yes)
			)
		)
		(property "Footprint" "antmicro-footprints:R_0402_1005Metric"
			(at 194.31 224.79 0)
			(effects
				(font
					(size 1.27 1.27)
					(thickness 0.15)
				)
				(justify left bottom)
				(hide yes)
			)
		)
		(property "Datasheet" "https://industrial.panasonic.com/cdbs/www-data/pdf/RDA0000/AOA0000C301.pdf"
			(at 194.31 227.33 0)
			(effects
				(font
					(size 1.27 1.27)
					(thickness 0.15)
				)
				(justify left bottom)
				(hide yes)
			)
		)
		(property "Description" "SMD Chip Resistor, Jumper, 0 ohm, 100 mW, 0402 [1005 Metric], Thick Film, General Purpose"
			(at 173.99 209.55 0)
			(effects
				(font
					(size 1.27 1.27)
				)
				(hide yes)
			)
		)
		(property "Manufacturer" "Panasonic"
			(at 194.31 232.41 0)
			(effects
				(font
					(size 1.27 1.27)
					(thickness 0.15)
				)
				(justify left bottom)
				(hide yes)
			)
		)
		(property "MPN" "ERJ2GE0R00X"
			(at 194.31 229.87 0)
			(effects
				(font
					(size 1.27 1.27)
					(thickness 0.15)
				)
				(justify left bottom)
				(hide yes)
			)
		)
		(property "Val" "0R"
			(at 180.34 208.28 0)
			(effects
				(font
					(size 1.27 1.27)
					(thickness 0.15)
				)
			)
		)
		(property "License" "Apache-2.0"
			(at 194.31 234.95 0)
			(effects
				(font
					(size 1.27 1.27)
					(thickness 0.15)
				)
				(justify left bottom)
				(hide yes)
			)
		)
		(property "Author" "Antmicro"
			(at 194.31 237.49 0)
			(effects
				(font
					(size 1.27 1.27)
					(thickness 0.15)
				)
				(justify left bottom)
				(hide yes)
			)
		)
		(property "Tolerance" "~"
			(at 194.31 219.71 0)
			(effects
				(font
					(size 1.27 1.27)
				)
				(justify left bottom)
				(hide yes)
			)
		)
		(property "Current" "1A"
			(at 120.65 222.25 0)
			(effects
				(font
					(size 1.27 1.27)
					(thickness 0.15)
				)
				(hide yes)
			)
		)
		(pin "1"
		)
		(pin "2"
		)
		(instances
			(project "artix-dc-scm"
				(path ""
					(reference "R104")
					(unit 1)
				)
			)
		)
	)
	(symbol
		(lib_id "antmicroResistors0402:R_0R_0402")
		(at 171.45 72.39 0)
		(unit 1)
		(exclude_from_sim no)
		(in_bom yes)
		(on_board yes)
		(dnp no)
		(property "Reference" "R115"
			(at 179.07 71.12 0)
			(effects
				(font
					(size 1.27 1.27)
				)
			)
		)
		(property "Value" "R_0R_0402"
			(at 191.77 85.09 0)
			(effects
				(font
					(size 1.27 1.27)
					(thickness 0.15)
				)
				(justify left bottom)
				(hide yes)
			)
		)
		(property "Footprint" "antmicro-footprints:R_0402_1005Metric"
			(at 191.77 87.63 0)
			(effects
				(font
					(size 1.27 1.27)
					(thickness 0.15)
				)
				(justify left bottom)
				(hide yes)
			)
		)
		(property "Datasheet" "https://industrial.panasonic.com/cdbs/www-data/pdf/RDA0000/AOA0000C301.pdf"
			(at 191.77 90.17 0)
			(effects
				(font
					(size 1.27 1.27)
					(thickness 0.15)
				)
				(justify left bottom)
				(hide yes)
			)
		)
		(property "Description" "SMD Chip Resistor, Jumper, 0 ohm, 100 mW, 0402 [1005 Metric], Thick Film, General Purpose"
			(at 171.45 72.39 0)
			(effects
				(font
					(size 1.27 1.27)
				)
				(hide yes)
			)
		)
		(property "Manufacturer" "Panasonic"
			(at 191.77 95.25 0)
			(effects
				(font
					(size 1.27 1.27)
					(thickness 0.15)
				)
				(justify left bottom)
				(hide yes)
			)
		)
		(property "MPN" "ERJ2GE0R00X"
			(at 191.77 92.71 0)
			(effects
				(font
					(size 1.27 1.27)
					(thickness 0.15)
				)
				(justify left bottom)
				(hide yes)
			)
		)
		(property "Val" "0R"
			(at 170.18 71.12 0)
			(effects
				(font
					(size 1.27 1.27)
					(thickness 0.15)
				)
			)
		)
		(property "License" "Apache-2.0"
			(at 191.77 97.79 0)
			(effects
				(font
					(size 1.27 1.27)
					(thickness 0.15)
				)
				(justify left bottom)
				(hide yes)
			)
		)
		(property "Author" "Antmicro"
			(at 191.77 100.33 0)
			(effects
				(font
					(size 1.27 1.27)
					(thickness 0.15)
				)
				(justify left bottom)
				(hide yes)
			)
		)
		(property "Tolerance" "~"
			(at 191.77 82.55 0)
			(effects
				(font
					(size 1.27 1.27)
				)
				(justify left bottom)
				(hide yes)
			)
		)
		(property "Current" "1A"
			(at 173.99 68.58 0)
			(effects
				(font
					(size 1.27 1.27)
					(thickness 0.15)
				)
				(hide yes)
			)
		)
		(pin "1"
		)
		(pin "2"
		)
		(instances
			(project "artix-dc-scm"
				(path ""
					(reference "R115")
					(unit 1)
				)
			)
		)
	)
	(symbol
		(lib_id "antmicropower:GND")
		(at 171.45 167.64 0)
		(unit 1)
		(exclude_from_sim no)
		(in_bom yes)
		(on_board yes)
		(dnp no)
		(property "Reference" "#PWR092"
			(at 171.45 173.99 0)
			(effects
				(font
					(size 1.27 1.27)
				)
				(hide yes)
			)
		)
		(property "Value" "GND"
			(at 171.45 171.45 0)
			(effects
				(font
					(size 1.27 1.27)
				)
			)
		)
		(property "Footprint" ""
			(at 171.45 167.64 0)
			(effects
				(font
					(size 1.27 1.27)
				)
				(hide yes)
			)
		)
		(property "Datasheet" ""
			(at 171.45 167.64 0)
			(effects
				(font
					(size 1.27 1.27)
				)
				(hide yes)
			)
		)
		(property "Description" ""
			(at 171.45 167.64 0)
			(effects
				(font
					(size 1.27 1.27)
				)
				(hide yes)
			)
		)
		(property "Author" "Antmicro"
			(at 180.34 175.26 0)
			(effects
				(font
					(size 1.27 1.27)
					(thickness 0.15)
				)
				(justify left bottom)
				(hide yes)
			)
		)
		(property "License" "Apache-2.0"
			(at 180.34 177.8 0)
			(effects
				(font
					(size 1.27 1.27)
					(thickness 0.15)
				)
				(justify left bottom)
				(hide yes)
			)
		)
		(pin "1"
		)
		(instances
			(project "artix-dc-scm"
				(path ""
					(reference "#PWR092")
					(unit 1)
				)
			)
		)
	)
	(symbol
		(lib_id "antmicroResistors0402:R_0R_0402")
		(at 292.1 72.39 0)
		(mirror y)
		(unit 1)
		(exclude_from_sim no)
		(in_bom yes)
		(on_board yes)
		(dnp no)
		(property "Reference" "R147"
			(at 284.48 71.12 0)
			(effects
				(font
					(size 1.27 1.27)
				)
			)
		)
		(property "Value" "R_0R_0402"
			(at 271.78 85.09 0)
			(effects
				(font
					(size 1.27 1.27)
					(thickness 0.15)
				)
				(justify left bottom)
				(hide yes)
			)
		)
		(property "Footprint" "antmicro-footprints:R_0402_1005Metric"
			(at 271.78 87.63 0)
			(effects
				(font
					(size 1.27 1.27)
					(thickness 0.15)
				)
				(justify left bottom)
				(hide yes)
			)
		)
		(property "Datasheet" "https://industrial.panasonic.com/cdbs/www-data/pdf/RDA0000/AOA0000C301.pdf"
			(at 271.78 90.17 0)
			(effects
				(font
					(size 1.27 1.27)
					(thickness 0.15)
				)
				(justify left bottom)
				(hide yes)
			)
		)
		(property "Description" "SMD Chip Resistor, Jumper, 0 ohm, 100 mW, 0402 [1005 Metric], Thick Film, General Purpose"
			(at 292.1 72.39 0)
			(effects
				(font
					(size 1.27 1.27)
				)
				(hide yes)
			)
		)
		(property "Manufacturer" "Panasonic"
			(at 271.78 95.25 0)
			(effects
				(font
					(size 1.27 1.27)
					(thickness 0.15)
				)
				(justify left bottom)
				(hide yes)
			)
		)
		(property "MPN" "ERJ2GE0R00X"
			(at 271.78 92.71 0)
			(effects
				(font
					(size 1.27 1.27)
					(thickness 0.15)
				)
				(justify left bottom)
				(hide yes)
			)
		)
		(property "Val" "0R"
			(at 293.37 71.12 0)
			(effects
				(font
					(size 1.27 1.27)
					(thickness 0.15)
				)
			)
		)
		(property "License" "Apache-2.0"
			(at 271.78 97.79 0)
			(effects
				(font
					(size 1.27 1.27)
					(thickness 0.15)
				)
				(justify left bottom)
				(hide yes)
			)
		)
		(property "Author" "Antmicro"
			(at 271.78 100.33 0)
			(effects
				(font
					(size 1.27 1.27)
					(thickness 0.15)
				)
				(justify left bottom)
				(hide yes)
			)
		)
		(property "Tolerance" "~"
			(at 271.78 82.55 0)
			(effects
				(font
					(size 1.27 1.27)
				)
				(justify left bottom)
				(hide yes)
			)
		)
		(property "Current" "1A"
			(at 289.56 68.58 0)
			(effects
				(font
					(size 1.27 1.27)
					(thickness 0.15)
				)
				(hide yes)
			)
		)
		(pin "1"
		)
		(pin "2"
		)
		(instances
			(project "artix-dc-scm"
				(path ""
					(reference "R147")
					(unit 1)
				)
			)
		)
	)
	(symbol
		(lib_id "antmicroResistors0402:R_0R_0402")
		(at 173.99 196.85 0)
		(unit 1)
		(exclude_from_sim no)
		(in_bom yes)
		(on_board yes)
		(dnp no)
		(property "Reference" "R101"
			(at 171.45 195.58 0)
			(effects
				(font
					(size 1.27 1.27)
				)
			)
		)
		(property "Value" "R_0R_0402"
			(at 194.31 209.55 0)
			(effects
				(font
					(size 1.27 1.27)
					(thickness 0.15)
				)
				(justify left bottom)
				(hide yes)
			)
		)
		(property "Footprint" "antmicro-footprints:R_0402_1005Metric"
			(at 194.31 212.09 0)
			(effects
				(font
					(size 1.27 1.27)
					(thickness 0.15)
				)
				(justify left bottom)
				(hide yes)
			)
		)
		(property "Datasheet" "https://industrial.panasonic.com/cdbs/www-data/pdf/RDA0000/AOA0000C301.pdf"
			(at 194.31 214.63 0)
			(effects
				(font
					(size 1.27 1.27)
					(thickness 0.15)
				)
				(justify left bottom)
				(hide yes)
			)
		)
		(property "Description" "SMD Chip Resistor, Jumper, 0 ohm, 100 mW, 0402 [1005 Metric], Thick Film, General Purpose"
			(at 173.99 196.85 0)
			(effects
				(font
					(size 1.27 1.27)
				)
				(hide yes)
			)
		)
		(property "Manufacturer" "Panasonic"
			(at 194.31 219.71 0)
			(effects
				(font
					(size 1.27 1.27)
					(thickness 0.15)
				)
				(justify left bottom)
				(hide yes)
			)
		)
		(property "MPN" "ERJ2GE0R00X"
			(at 194.31 217.17 0)
			(effects
				(font
					(size 1.27 1.27)
					(thickness 0.15)
				)
				(justify left bottom)
				(hide yes)
			)
		)
		(property "Val" "0R"
			(at 180.34 195.58 0)
			(effects
				(font
					(size 1.27 1.27)
					(thickness 0.15)
				)
			)
		)
		(property "License" "Apache-2.0"
			(at 194.31 222.25 0)
			(effects
				(font
					(size 1.27 1.27)
					(thickness 0.15)
				)
				(justify left bottom)
				(hide yes)
			)
		)
		(property "Author" "Antmicro"
			(at 194.31 224.79 0)
			(effects
				(font
					(size 1.27 1.27)
					(thickness 0.15)
				)
				(justify left bottom)
				(hide yes)
			)
		)
		(property "Tolerance" "~"
			(at 194.31 207.01 0)
			(effects
				(font
					(size 1.27 1.27)
				)
				(justify left bottom)
				(hide yes)
			)
		)
		(property "Current" "1A"
			(at 121.92 208.28 0)
			(effects
				(font
					(size 1.27 1.27)
					(thickness 0.15)
				)
				(hide yes)
			)
		)
		(pin "1"
		)
		(pin "2"
		)
		(instances
			(project "artix-dc-scm"
				(path ""
					(reference "R101")
					(unit 1)
				)
			)
		)
	)
	(symbol
		(lib_id "antmicroResistors0402:R_0R_0402")
		(at 179.07 227.33 0)
		(mirror y)
		(unit 1)
		(exclude_from_sim no)
		(in_bom yes)
		(on_board yes)
		(dnp no)
		(property "Reference" "R111"
			(at 171.45 226.06 0)
			(effects
				(font
					(size 1.27 1.27)
				)
			)
		)
		(property "Value" "R_0R_0402"
			(at 158.75 240.03 0)
			(effects
				(font
					(size 1.27 1.27)
					(thickness 0.15)
				)
				(justify left bottom)
				(hide yes)
			)
		)
		(property "Footprint" "antmicro-footprints:R_0402_1005Metric"
			(at 158.75 242.57 0)
			(effects
				(font
					(size 1.27 1.27)
					(thickness 0.15)
				)
				(justify left bottom)
				(hide yes)
			)
		)
		(property "Datasheet" "https://industrial.panasonic.com/cdbs/www-data/pdf/RDA0000/AOA0000C301.pdf"
			(at 158.75 245.11 0)
			(effects
				(font
					(size 1.27 1.27)
					(thickness 0.15)
				)
				(justify left bottom)
				(hide yes)
			)
		)
		(property "Description" "SMD Chip Resistor, Jumper, 0 ohm, 100 mW, 0402 [1005 Metric], Thick Film, General Purpose"
			(at 179.07 227.33 0)
			(effects
				(font
					(size 1.27 1.27)
				)
				(hide yes)
			)
		)
		(property "Manufacturer" "Panasonic"
			(at 158.75 250.19 0)
			(effects
				(font
					(size 1.27 1.27)
					(thickness 0.15)
				)
				(justify left bottom)
				(hide yes)
			)
		)
		(property "MPN" "ERJ2GE0R00X"
			(at 158.75 247.65 0)
			(effects
				(font
					(size 1.27 1.27)
					(thickness 0.15)
				)
				(justify left bottom)
				(hide yes)
			)
		)
		(property "Val" "0R"
			(at 180.975 226.06 0)
			(effects
				(font
					(size 1.27 1.27)
					(thickness 0.15)
				)
			)
		)
		(property "License" "Apache-2.0"
			(at 158.75 252.73 0)
			(effects
				(font
					(size 1.27 1.27)
					(thickness 0.15)
				)
				(justify left bottom)
				(hide yes)
			)
		)
		(property "Author" "Antmicro"
			(at 158.75 255.27 0)
			(effects
				(font
					(size 1.27 1.27)
					(thickness 0.15)
				)
				(justify left bottom)
				(hide yes)
			)
		)
		(property "Tolerance" "~"
			(at 158.75 237.49 0)
			(effects
				(font
					(size 1.27 1.27)
				)
				(justify left bottom)
				(hide yes)
			)
		)
		(property "Current" "1A"
			(at 234.315 238.125 0)
			(effects
				(font
					(size 1.27 1.27)
					(thickness 0.15)
				)
				(hide yes)
			)
		)
		(pin "1"
		)
		(pin "2"
		)
		(instances
			(project "artix-dc-scm"
				(path ""
					(reference "R111")
					(unit 1)
				)
			)
		)
	)
	(symbol
		(lib_id "antmicroResistors0402:R_0R_0402")
		(at 179.07 224.79 0)
		(mirror y)
		(unit 1)
		(exclude_from_sim no)
		(in_bom yes)
		(on_board yes)
		(dnp no)
		(property "Reference" "R110"
			(at 171.45 223.52 0)
			(effects
				(font
					(size 1.27 1.27)
				)
			)
		)
		(property "Value" "R_0R_0402"
			(at 158.75 237.49 0)
			(effects
				(font
					(size 1.27 1.27)
					(thickness 0.15)
				)
				(justify left bottom)
				(hide yes)
			)
		)
		(property "Footprint" "antmicro-footprints:R_0402_1005Metric"
			(at 158.75 240.03 0)
			(effects
				(font
					(size 1.27 1.27)
					(thickness 0.15)
				)
				(justify left bottom)
				(hide yes)
			)
		)
		(property "Datasheet" "https://industrial.panasonic.com/cdbs/www-data/pdf/RDA0000/AOA0000C301.pdf"
			(at 158.75 242.57 0)
			(effects
				(font
					(size 1.27 1.27)
					(thickness 0.15)
				)
				(justify left bottom)
				(hide yes)
			)
		)
		(property "Description" "SMD Chip Resistor, Jumper, 0 ohm, 100 mW, 0402 [1005 Metric], Thick Film, General Purpose"
			(at 179.07 224.79 0)
			(effects
				(font
					(size 1.27 1.27)
				)
				(hide yes)
			)
		)
		(property "Manufacturer" "Panasonic"
			(at 158.75 247.65 0)
			(effects
				(font
					(size 1.27 1.27)
					(thickness 0.15)
				)
				(justify left bottom)
				(hide yes)
			)
		)
		(property "MPN" "ERJ2GE0R00X"
			(at 158.75 245.11 0)
			(effects
				(font
					(size 1.27 1.27)
					(thickness 0.15)
				)
				(justify left bottom)
				(hide yes)
			)
		)
		(property "Val" "0R"
			(at 180.975 223.52 0)
			(effects
				(font
					(size 1.27 1.27)
					(thickness 0.15)
				)
			)
		)
		(property "License" "Apache-2.0"
			(at 158.75 250.19 0)
			(effects
				(font
					(size 1.27 1.27)
					(thickness 0.15)
				)
				(justify left bottom)
				(hide yes)
			)
		)
		(property "Author" "Antmicro"
			(at 158.75 252.73 0)
			(effects
				(font
					(size 1.27 1.27)
					(thickness 0.15)
				)
				(justify left bottom)
				(hide yes)
			)
		)
		(property "Tolerance" "~"
			(at 158.75 234.95 0)
			(effects
				(font
					(size 1.27 1.27)
				)
				(justify left bottom)
				(hide yes)
			)
		)
		(property "Current" "1A"
			(at 232.41 233.045 0)
			(effects
				(font
					(size 1.27 1.27)
					(thickness 0.15)
				)
				(hide yes)
			)
		)
		(pin "1"
		)
		(pin "2"
		)
		(instances
			(project "artix-dc-scm"
				(path ""
					(reference "R110")
					(unit 1)
				)
			)
		)
	)
	(symbol
		(lib_id "antmicroResistors0402:R_0R_0402")
		(at 173.99 222.25 0)
		(unit 1)
		(exclude_from_sim no)
		(in_bom yes)
		(on_board yes)
		(dnp no)
		(property "Reference" "R109"
			(at 171.45 220.98 0)
			(effects
				(font
					(size 1.27 1.27)
				)
			)
		)
		(property "Value" "R_0R_0402"
			(at 194.31 234.95 0)
			(effects
				(font
					(size 1.27 1.27)
					(thickness 0.15)
				)
				(justify left bottom)
				(hide yes)
			)
		)
		(property "Footprint" "antmicro-footprints:R_0402_1005Metric"
			(at 194.31 237.49 0)
			(effects
				(font
					(size 1.27 1.27)
					(thickness 0.15)
				)
				(justify left bottom)
				(hide yes)
			)
		)
		(property "Datasheet" "https://industrial.panasonic.com/cdbs/www-data/pdf/RDA0000/AOA0000C301.pdf"
			(at 194.31 240.03 0)
			(effects
				(font
					(size 1.27 1.27)
					(thickness 0.15)
				)
				(justify left bottom)
				(hide yes)
			)
		)
		(property "Description" "SMD Chip Resistor, Jumper, 0 ohm, 100 mW, 0402 [1005 Metric], Thick Film, General Purpose"
			(at 173.99 222.25 0)
			(effects
				(font
					(size 1.27 1.27)
				)
				(hide yes)
			)
		)
		(property "Manufacturer" "Panasonic"
			(at 194.31 245.11 0)
			(effects
				(font
					(size 1.27 1.27)
					(thickness 0.15)
				)
				(justify left bottom)
				(hide yes)
			)
		)
		(property "MPN" "ERJ2GE0R00X"
			(at 194.31 242.57 0)
			(effects
				(font
					(size 1.27 1.27)
					(thickness 0.15)
				)
				(justify left bottom)
				(hide yes)
			)
		)
		(property "Val" "0R"
			(at 180.34 220.98 0)
			(effects
				(font
					(size 1.27 1.27)
					(thickness 0.15)
				)
			)
		)
		(property "License" "Apache-2.0"
			(at 194.31 247.65 0)
			(effects
				(font
					(size 1.27 1.27)
					(thickness 0.15)
				)
				(justify left bottom)
				(hide yes)
			)
		)
		(property "Author" "Antmicro"
			(at 194.31 250.19 0)
			(effects
				(font
					(size 1.27 1.27)
					(thickness 0.15)
				)
				(justify left bottom)
				(hide yes)
			)
		)
		(property "Tolerance" "~"
			(at 194.31 232.41 0)
			(effects
				(font
					(size 1.27 1.27)
				)
				(justify left bottom)
				(hide yes)
			)
		)
		(property "Current" "1A"
			(at 121.285 233.68 0)
			(effects
				(font
					(size 1.27 1.27)
					(thickness 0.15)
				)
				(hide yes)
			)
		)
		(pin "1"
		)
		(pin "2"
		)
		(instances
			(project "artix-dc-scm"
				(path ""
					(reference "R109")
					(unit 1)
				)
			)
		)
	)
	(symbol
		(lib_id "antmicroResistors0402:R_0R_0402")
		(at 254 44.45 0)
		(mirror y)
		(unit 1)
		(exclude_from_sim no)
		(in_bom yes)
		(on_board yes)
		(dnp no)
		(property "Reference" "R114"
			(at 246.38 43.18 0)
			(effects
				(font
					(size 1.27 1.27)
				)
			)
		)
		(property "Value" "R_0R_0402"
			(at 233.68 57.15 0)
			(effects
				(font
					(size 1.27 1.27)
					(thickness 0.15)
				)
				(justify left bottom)
				(hide yes)
			)
		)
		(property "Footprint" "antmicro-footprints:R_0402_1005Metric"
			(at 233.68 59.69 0)
			(effects
				(font
					(size 1.27 1.27)
					(thickness 0.15)
				)
				(justify left bottom)
				(hide yes)
			)
		)
		(property "Datasheet" "https://industrial.panasonic.com/cdbs/www-data/pdf/RDA0000/AOA0000C301.pdf"
			(at 233.68 62.23 0)
			(effects
				(font
					(size 1.27 1.27)
					(thickness 0.15)
				)
				(justify left bottom)
				(hide yes)
			)
		)
		(property "Description" "SMD Chip Resistor, Jumper, 0 ohm, 100 mW, 0402 [1005 Metric], Thick Film, General Purpose"
			(at 254 44.45 0)
			(effects
				(font
					(size 1.27 1.27)
				)
				(hide yes)
			)
		)
		(property "Manufacturer" "Panasonic"
			(at 233.68 67.31 0)
			(effects
				(font
					(size 1.27 1.27)
					(thickness 0.15)
				)
				(justify left bottom)
				(hide yes)
			)
		)
		(property "MPN" "ERJ2GE0R00X"
			(at 233.68 64.77 0)
			(effects
				(font
					(size 1.27 1.27)
					(thickness 0.15)
				)
				(justify left bottom)
				(hide yes)
			)
		)
		(property "Val" "0R"
			(at 255.905 43.18 0)
			(effects
				(font
					(size 1.27 1.27)
					(thickness 0.15)
				)
			)
		)
		(property "License" "Apache-2.0"
			(at 233.68 69.85 0)
			(effects
				(font
					(size 1.27 1.27)
					(thickness 0.15)
				)
				(justify left bottom)
				(hide yes)
			)
		)
		(property "Author" "Antmicro"
			(at 233.68 72.39 0)
			(effects
				(font
					(size 1.27 1.27)
					(thickness 0.15)
				)
				(justify left bottom)
				(hide yes)
			)
		)
		(property "Tolerance" "~"
			(at 233.68 54.61 0)
			(effects
				(font
					(size 1.27 1.27)
				)
				(justify left bottom)
				(hide yes)
			)
		)
		(property "Current" "1A"
			(at 251.46 53.34 0)
			(effects
				(font
					(size 1.27 1.27)
					(thickness 0.15)
				)
				(hide yes)
			)
		)
		(pin "1"
		)
		(pin "2"
		)
		(instances
			(project "artix-dc-scm"
				(path ""
					(reference "R114")
					(unit 1)
				)
			)
		)
	)
	(symbol
		(lib_id "antmicroResistors0402:R_0R_0402")
		(at 173.99 204.47 0)
		(unit 1)
		(exclude_from_sim no)
		(in_bom yes)
		(on_board yes)
		(dnp no)
		(property "Reference" "R102"
			(at 171.45 203.2 0)
			(effects
				(font
					(size 1.27 1.27)
				)
			)
		)
		(property "Value" "R_0R_0402"
			(at 194.31 217.17 0)
			(effects
				(font
					(size 1.27 1.27)
					(thickness 0.15)
				)
				(justify left bottom)
				(hide yes)
			)
		)
		(property "Footprint" "antmicro-footprints:R_0402_1005Metric"
			(at 194.31 219.71 0)
			(effects
				(font
					(size 1.27 1.27)
					(thickness 0.15)
				)
				(justify left bottom)
				(hide yes)
			)
		)
		(property "Datasheet" "https://industrial.panasonic.com/cdbs/www-data/pdf/RDA0000/AOA0000C301.pdf"
			(at 194.31 222.25 0)
			(effects
				(font
					(size 1.27 1.27)
					(thickness 0.15)
				)
				(justify left bottom)
				(hide yes)
			)
		)
		(property "Description" "SMD Chip Resistor, Jumper, 0 ohm, 100 mW, 0402 [1005 Metric], Thick Film, General Purpose"
			(at 173.99 204.47 0)
			(effects
				(font
					(size 1.27 1.27)
				)
				(hide yes)
			)
		)
		(property "Manufacturer" "Panasonic"
			(at 194.31 227.33 0)
			(effects
				(font
					(size 1.27 1.27)
					(thickness 0.15)
				)
				(justify left bottom)
				(hide yes)
			)
		)
		(property "MPN" "ERJ2GE0R00X"
			(at 194.31 224.79 0)
			(effects
				(font
					(size 1.27 1.27)
					(thickness 0.15)
				)
				(justify left bottom)
				(hide yes)
			)
		)
		(property "Val" "0R"
			(at 180.34 203.2 0)
			(effects
				(font
					(size 1.27 1.27)
					(thickness 0.15)
				)
			)
		)
		(property "License" "Apache-2.0"
			(at 194.31 229.87 0)
			(effects
				(font
					(size 1.27 1.27)
					(thickness 0.15)
				)
				(justify left bottom)
				(hide yes)
			)
		)
		(property "Author" "Antmicro"
			(at 194.31 232.41 0)
			(effects
				(font
					(size 1.27 1.27)
					(thickness 0.15)
				)
				(justify left bottom)
				(hide yes)
			)
		)
		(property "Tolerance" "~"
			(at 194.31 214.63 0)
			(effects
				(font
					(size 1.27 1.27)
				)
				(justify left bottom)
				(hide yes)
			)
		)
		(property "Current" "1A"
			(at 115.57 216.535 0)
			(effects
				(font
					(size 1.27 1.27)
					(thickness 0.15)
				)
				(hide yes)
			)
		)
		(pin "1"
		)
		(pin "2"
		)
		(instances
			(project "artix-dc-scm"
				(path ""
					(reference "R102")
					(unit 1)
				)
			)
		)
	)
)
